FILE_TYPE = MACRO_DRAWING;
SET COLOR_WIRE YELLOW;
SET COLOR_PROP MONO;
SET COLOR_DOT WHITE;
SET COLOR_ARC YELLOW;
SET COLOR_BODY GREEN;
SET COLOR_NOTE MONO;
SET PROP_DISPLAY VALUE;
SET PAGE_NUMBER P98;
FORCEADD PVDDQ_ABC..1
(-1800 4600);
FORCEPROP 3 LASTPIN (-1800 4550) SIG_NAME PVDDQ_ABC\g
J 0
(-1790 4560);
DISPLAY 0.659574 (-1790 4560);
PAINT MONO (-1790 4560);
DISPLAY INVISIBLE (-1790 4560);
FORCEPROP 1 LAST VOLTAGE 1.2V
J 0
(-1845 4557);
DISPLAY 0.340426 (-1845 4557);
PAINT SKYBLUE (-1845 4557);
DISPLAY INVISIBLE (-1845 4557);
FORCEPROP 2 LAST CDS_LIB mstr_symbols
J 0
(-1800 4600);
PAINT ORANGE (-1800 4600);
DISPLAY INVISIBLE (-1800 4600);
FORCEPROP 1 LAST BODY_TYPE PLUMBING
J 0
(-1845 4557);
DISPLAY 0.340426 (-1845 4557);
PAINT GREEN (-1845 4557);
DISPLAY INVISIBLE (-1845 4557);
FORCEPROP 1 LAST PATH I1
J 0
(-1750 4625);
DISPLAY 0.872340 (-1750 4625);
PAINT AQUA (-1750 4625);
DISPLAY INVISIBLE (-1750 4625);
FORCEPROP 1 LAST HDL_POWER PVDDQ_ABC
J 1
(-1800 4650);
DISPLAY 0.872340 (-1800 4650);
PAINT GREEN (-1800 4650);
DISPLAY INVISIBLE (-1800 4650);
FORCEADD PVDDQ_DEF..1
(-1800 2925);
FORCEPROP 3 LASTPIN (-1800 2875) SIG_NAME PVDDQ_DEF\g
J 0
(-1790 2885);
DISPLAY 0.659574 (-1790 2885);
PAINT MONO (-1790 2885);
DISPLAY INVISIBLE (-1790 2885);
FORCEPROP 1 LAST VOLTAGE 1.2V
J 0
(-1845 2882);
DISPLAY 0.340426 (-1845 2882);
PAINT SKYBLUE (-1845 2882);
DISPLAY INVISIBLE (-1845 2882);
FORCEPROP 2 LAST CDS_LIB mstr_symbols
J 0
(-1800 2925);
PAINT ORANGE (-1800 2925);
DISPLAY INVISIBLE (-1800 2925);
FORCEPROP 1 LAST BODY_TYPE PLUMBING
J 0
(-1845 2882);
DISPLAY 0.340426 (-1845 2882);
PAINT GREEN (-1845 2882);
DISPLAY INVISIBLE (-1845 2882);
FORCEPROP 1 LAST PATH I10
J 0
(-1750 2950);
DISPLAY 0.872340 (-1750 2950);
PAINT AQUA (-1750 2950);
DISPLAY INVISIBLE (-1750 2950);
FORCEPROP 1 LAST HDL_POWER PVDDQ_DEF
J 1
(-1800 2975);
DISPLAY 0.872340 (-1800 2975);
PAINT GREEN (-1800 2975);
DISPLAY INVISIBLE (-1800 2975);
FORCEADD OFFPAGE..2
(-1375 2350);
FORCEPROP 2 LAST $XR1 50 
J 0
(-1096 2350);
DISPLAY 0.638298 (-1096 2350);
PAINT MONO (-1096 2350);
FORCEPROP 2 LAST $XR0 49 
J 0
(-1186 2350);
DISPLAY 0.638298 (-1186 2350);
PAINT MONO (-1186 2350);
FORCEPROP 2 LAST CDS_LIB mstr_standard
J 0
(-1375 2350);
PAINT MONO (-1375 2350);
DISPLAY INVISIBLE (-1375 2350);
FORCEPROP 1 LAST OFFPAGE TRUE
J 0
(-1050 2225);
PAINT GREEN (-1050 2225);
DISPLAY INVISIBLE (-1050 2225);
FORCEPROP 1 LAST COMMENT_BODY TRUE
J 0
(-1420 2255);
DISPLAY 1.170213 (-1420 2255);
PAINT GREEN (-1420 2255);
DISPLAY INVISIBLE (-1420 2255);
FORCEPROP 2 LAST PATH I11
J 0
(-1075 2400);
DISPLAY 1.021277 (-1075 2400);
PAINT ORANGE (-1075 2400);
DISPLAY INVISIBLE (-1075 2400);
FORCEADD RES..2
R 2
(-1725 2025);
FORCEPROP 1 LAST LOCATION R6L16
J 2
(-1770 2150);
DISPLAY 0.617021 (-1770 2150);
PAINT AQUA (-1770 2150);
FORCEPROP 1 LAST PART_NUMBER G21796-026
J 2
(-1765 1900);
DISPLAY 0.617021 (-1765 1900);
PAINT BLUE (-1765 1900);
FORCEPROP 1 LAST VALUE 1.00K
J 2
(-1770 2100);
DISPLAY 0.617021 (-1770 2100);
PAINT SKYBLUE (-1770 2100);
FORCEPROP 1 LAST TOLERANCE 1%
J 2
(-1770 2050);
DISPLAY 0.617021 (-1770 2050);
PAINT SKYBLUE (-1770 2050);
FORCEPROP 1 LAST PACK_TYPE 0402
J 2
(-1765 1850);
DISPLAY 0.617021 (-1765 1850);
PAINT SKYBLUE (-1765 1850);
FORCEPROP 1 LAST MATERIAL CHIP
J 2
(-1765 1950);
DISPLAY 0.617021 (-1765 1950);
PAINT SKYBLUE (-1765 1950);
FORCEPROP 1 LAST WATTAGE 1/16W
J 2
(-1765 2000);
DISPLAY 0.617021 (-1765 2000);
PAINT SKYBLUE (-1765 2000);
FORCEPROP 1 LASTPIN (-1725 1925) $PN 2
J 2
(-1730 1935);
DISPLAY 0.617021 (-1730 1935);
PAINT ORANGE (-1730 1935);
FORCEPROP 1 LASTPIN (-1725 2125) $PN 1
J 2
(-1730 2087);
DISPLAY 0.617021 (-1730 2087);
PAINT ORANGE (-1730 2087);
FORCEPROP 2 LAST CDS_LIB mstr_discrete
J 0
(-1725 2025);
PAINT ORANGE (-1725 2025);
DISPLAY INVISIBLE (-1725 2025);
FORCEPROP 2 LAST BOM_COST PROC_SOCKET
J 2
(-1725 2025);
PAINT MONO (-1725 2025);
DISPLAY INVISIBLE (-1725 2025);
FORCEPROP 2 LAST SEC_TYPE 0402
J 0
(-1775 2250);
DISPLAY 1.021277 (-1775 2250);
PAINT ORANGE (-1775 2250);
DISPLAY INVISIBLE (-1775 2250);
FORCEPROP 2 LAST SEC 1
J 0
(-1775 2250);
DISPLAY 0.680851 (-1775 2250);
PAINT MONO (-1775 2250);
DISPLAY INVISIBLE (-1775 2250);
FORCEPROP 2 LAST CDS_LOCATION R6L16
J 2
(-1770 2150);
DISPLAY 0.617021 (-1770 2150);
PAINT AQUA (-1770 2150);
DISPLAY INVISIBLE (-1770 2150);
FORCEPROP 1 LAST PATH I12
J 2
(-1775 2200);
DISPLAY 0.978723 (-1775 2200);
PAINT WHITE (-1775 2200);
DISPLAY INVISIBLE (-1775 2200);
FORCEPROP 2 LAST ROOM PROC
J 2
(-1775 2200);
PAINT PEACH (-1775 2200);
DISPLAY INVISIBLE (-1775 2200);
FORCEADD GND..1
(-2025 1700);
FORCEPROP 3 LASTPIN (-2025 1750) SIG_NAME GND\g
J 0
(-2015 1760);
DISPLAY 0.659574 (-2015 1760);
PAINT MONO (-2015 1760);
DISPLAY INVISIBLE (-2015 1760);
FORCEPROP 1 LAST VOLTAGE 0
J 0
(-2025 1700);
PAINT SKYBLUE (-2025 1700);
DISPLAY INVISIBLE (-2025 1700);
FORCEPROP 2 LAST CDS_LIB mstr_symbols
J 0
(-2025 1700);
PAINT MONO (-2025 1700);
DISPLAY INVISIBLE (-2025 1700);
FORCEPROP 1 LAST SIZE 1B
J 0
(-1950 1650);
DISPLAY 1.170213 (-1950 1650);
PAINT GREEN (-1950 1650);
DISPLAY INVISIBLE (-1950 1650);
FORCEPROP 1 LAST BODY_TYPE PLUMBING
J 0
(-2070 1657);
DISPLAY 0.340426 (-2070 1657);
PAINT GREEN (-2070 1657);
DISPLAY INVISIBLE (-2070 1657);
FORCEPROP 1 LAST PATH I13
J 0
(-1950 1700);
DISPLAY 0.872340 (-1950 1700);
PAINT AQUA (-1950 1700);
DISPLAY INVISIBLE (-1950 1700);
FORCEPROP 1 LAST HDL_POWER GND
J 0
(-2025 1850);
DISPLAY 1.170213 (-2025 1850);
PAINT GREEN (-2025 1850);
DISPLAY INVISIBLE (-2025 1850);
FORCEADD RES..1
(-2025 2350);
FORCEPROP 1 LAST LOCATION R6M2
J 0
(-2050 2425);
DISPLAY 0.617021 (-2050 2425);
PAINT AQUA (-2050 2425);
FORCEPROP 1 LAST PART_NUMBER G21796-274
J 0
(-2150 2200);
DISPLAY 0.617021 (-2150 2200);
PAINT BLUE (-2150 2200);
FORCEPROP 1 LAST VALUE 2
J 2
(-2100 2300);
DISPLAY 0.617021 (-2100 2300);
PAINT SKYBLUE (-2100 2300);
FORCEPROP 1 LAST TOLERANCE 1.0%
J 0
(-1925 2250);
DISPLAY 0.617021 (-1925 2250);
PAINT SKYBLUE (-1925 2250);
FORCEPROP 1 LAST PACK_TYPE 0402
J 0
(-2150 2250);
DISPLAY 0.617021 (-2150 2250);
PAINT SKYBLUE (-2150 2250);
FORCEPROP 1 LAST MATERIAL CHIP
J 0
(-1800 2300);
DISPLAY 0.617021 (-1800 2300);
PAINT SKYBLUE (-1800 2300);
FORCEPROP 1 LAST WATTAGE 1/16W
J 2
(-1850 2300);
DISPLAY 0.617021 (-1850 2300);
PAINT SKYBLUE (-1850 2300);
FORCEPROP 1 LASTPIN (-1925 2350) $PN 2
J 0
(-1963 2362);
DISPLAY 0.617021 (-1963 2362);
PAINT MONO (-1963 2362);
FORCEPROP 1 LASTPIN (-2125 2350) $PN 1
J 0
(-2113 2362);
DISPLAY 0.617021 (-2113 2362);
PAINT MONO (-2113 2362);
FORCEPROP 2 LAST CDS_LIB mstr_discrete
J 0
(-2025 2350);
PAINT ORANGE (-2025 2350);
DISPLAY INVISIBLE (-2025 2350);
FORCEPROP 2 LAST BOM_COST PROC_SOCKET
J 0
(-2025 2350);
PAINT MONO (-2025 2350);
DISPLAY INVISIBLE (-2025 2350);
FORCEPROP 2 LAST SEC_TYPE 0402
J 0
(-2075 2550);
PAINT MONO (-2075 2550);
DISPLAY INVISIBLE (-2075 2550);
FORCEPROP 2 LAST SEC 1
J 0
(-2075 2550);
DISPLAY 0.936170 (-2075 2550);
PAINT MONO (-2075 2550);
DISPLAY INVISIBLE (-2075 2550);
FORCEPROP 2 LAST CDS_LOCATION R6M2
J 0
(-2050 2425);
DISPLAY 0.617021 (-2050 2425);
PAINT AQUA (-2050 2425);
DISPLAY INVISIBLE (-2050 2425);
FORCEPROP 1 LAST PATH I14
J 0
(-2075 2500);
DISPLAY 0.978723 (-2075 2500);
PAINT WHITE (-2075 2500);
DISPLAY INVISIBLE (-2075 2500);
FORCEPROP 0 LAST ROOM PROC
J 0
(-2100 2275);
DISPLAY 0.617021 (-2100 2275);
PAINT ORANGE (-2100 2275);
DISPLAY INVISIBLE (-2100 2275);
FORCEADD OFFPAGE..1
(-2750 2350);
FORCEPROP 2 LAST $XR0 21 
J 0
(-2971 2350);
DISPLAY 0.638298 (-2971 2350);
PAINT MONO (-2971 2350);
FORCEPROP 2 LAST CDS_LIB mstr_standard
J 0
(-2750 2350);
PAINT MONO (-2750 2350);
DISPLAY INVISIBLE (-2750 2350);
FORCEPROP 1 LAST OFFPAGE TRUE
J 0
(-2425 2225);
PAINT GREEN (-2425 2225);
DISPLAY INVISIBLE (-2425 2225);
FORCEPROP 1 LAST COMMENT_BODY TRUE
J 0
(-2625 2250);
DISPLAY 1.170213 (-2625 2250);
PAINT GREEN (-2625 2250);
DISPLAY INVISIBLE (-2625 2250);
FORCEPROP 2 LAST PATH I16
J 0
(-3000 2400);
DISPLAY 1.021277 (-3000 2400);
PAINT ORANGE (-3000 2400);
DISPLAY INVISIBLE (-3000 2400);
FORCEADD OFFPAGE..2
(-1375 4025);
FORCEPROP 2 LAST $XR1 44 
J 0
(-1096 4025);
DISPLAY 0.638298 (-1096 4025);
PAINT MONO (-1096 4025);
FORCEPROP 2 LAST $XR0 43 
J 0
(-1186 4025);
DISPLAY 0.638298 (-1186 4025);
PAINT MONO (-1186 4025);
FORCEPROP 2 LAST CDS_LIB mstr_standard
J 0
(-1375 4025);
PAINT MONO (-1375 4025);
DISPLAY INVISIBLE (-1375 4025);
FORCEPROP 1 LAST OFFPAGE TRUE
J 0
(-1050 3900);
PAINT GREEN (-1050 3900);
DISPLAY INVISIBLE (-1050 3900);
FORCEPROP 1 LAST COMMENT_BODY TRUE
J 0
(-1420 3930);
DISPLAY 1.170213 (-1420 3930);
PAINT GREEN (-1420 3930);
DISPLAY INVISIBLE (-1420 3930);
FORCEPROP 2 LAST PATH I3
J 0
(-1075 4075);
DISPLAY 1.021277 (-1075 4075);
PAINT ORANGE (-1075 4075);
DISPLAY INVISIBLE (-1075 4075);
FORCEADD CAP_A..1
(-2250 2050);
FORCEPROP 1 LAST LOCATION C6M2
J 0
(-2200 2150);
DISPLAY 0.617021 (-2200 2150);
PAINT AQUA (-2200 2150);
FORCEPROP 1 LAST PART_NUMBER A36096-045
J 0
(-2200 1900);
DISPLAY 0.617021 (-2200 1900);
PAINT BLUE (-2200 1900);
FORCEPROP 1 LAST VALUE 0.01UF
J 0
(-2200 2100);
DISPLAY 0.617021 (-2200 2100);
PAINT SKYBLUE (-2200 2100);
FORCEPROP 1 LAST TOLERANCE 10%
J 0
(-2200 2000);
DISPLAY 0.617021 (-2200 2000);
PAINT SKYBLUE (-2200 2000);
FORCEPROP 1 LAST PACK_TYPE 0402V
J 0
(-2200 1850);
DISPLAY 0.617021 (-2200 1850);
PAINT SKYBLUE (-2200 1850);
FORCEPROP 1 LAST VOLTAGE 25V
J 0
(-2200 2050);
DISPLAY 0.617021 (-2200 2050);
PAINT SKYBLUE (-2200 2050);
FORCEPROP 1 LAST MATERIAL X7R
J 0
(-2200 1950);
DISPLAY 0.617021 (-2200 1950);
PAINT SKYBLUE (-2200 1950);
FORCEPROP 1 LASTPIN (-2250 2150) $PN 1
J 0
(-2240 2130);
DISPLAY 0.617021 (-2240 2130);
PAINT ORANGE (-2240 2130);
FORCEPROP 1 LASTPIN (-2250 1950) $PN 2
J 0
(-2240 1930);
DISPLAY 0.617021 (-2240 1930);
PAINT ORANGE (-2240 1930);
FORCEPROP 2 LAST CDS_LOCATION C6M2
J 0
(-2200 2150);
DISPLAY 0.617021 (-2200 2150);
PAINT AQUA (-2200 2150);
DISPLAY INVISIBLE (-2200 2150);
FORCEPROP 2 LAST BOM_COST SM_CONTROLLER
J 0
(-2250 2050);
PAINT MONO (-2250 2050);
DISPLAY INVISIBLE (-2250 2050);
FORCEPROP 2 LAST CDS_LIB dev_discrete
J 0
(-2250 2050);
PAINT ORANGE (-2250 2050);
DISPLAY INVISIBLE (-2250 2050);
FORCEPROP 2 LAST CDS_SEC 1
J 0
(-2200 2200);
PAINT ORANGE (-2200 2200);
DISPLAY INVISIBLE (-2200 2200);
FORCEPROP 2 LAST SEC_TYPE 0402V
J 0
(-2200 2250);
DISPLAY 1.021277 (-2200 2250);
PAINT ORANGE (-2200 2250);
DISPLAY INVISIBLE (-2200 2250);
FORCEPROP 2 LAST SEC 1
J 0
(-2200 2250);
DISPLAY 0.680851 (-2200 2250);
PAINT MONO (-2200 2250);
DISPLAY INVISIBLE (-2200 2250);
FORCEPROP 1 LAST PATH I33
J 0
(-2200 2200);
DISPLAY 0.978723 (-2200 2200);
PAINT WHITE (-2200 2200);
DISPLAY INVISIBLE (-2200 2200);
FORCEPROP 0 LAST ROOM MEM
J 0
(-2200 1800);
DISPLAY 0.978723 (-2200 1800);
PAINT ORANGE (-2200 1800);
DISPLAY INVISIBLE (-2200 1800);
FORCEADD RES..2
R 2
(-1800 4350);
FORCEPROP 1 LAST LOCATION R4F4
J 2
(-1845 4475);
DISPLAY 0.617021 (-1845 4475);
PAINT AQUA (-1845 4475);
FORCEPROP 1 LAST PART_NUMBER G21796-026
J 2
(-1840 4225);
DISPLAY 0.617021 (-1840 4225);
PAINT BLUE (-1840 4225);
FORCEPROP 1 LAST VALUE 1.00K
J 2
(-1845 4425);
DISPLAY 0.617021 (-1845 4425);
PAINT SKYBLUE (-1845 4425);
FORCEPROP 1 LAST TOLERANCE 1%
J 2
(-1845 4375);
DISPLAY 0.617021 (-1845 4375);
PAINT SKYBLUE (-1845 4375);
FORCEPROP 1 LAST PACK_TYPE 0402
J 2
(-1840 4175);
DISPLAY 0.617021 (-1840 4175);
PAINT SKYBLUE (-1840 4175);
FORCEPROP 1 LAST MATERIAL CHIP
J 2
(-1840 4275);
DISPLAY 0.617021 (-1840 4275);
PAINT SKYBLUE (-1840 4275);
FORCEPROP 1 LAST WATTAGE 1/16W
J 2
(-1840 4325);
DISPLAY 0.617021 (-1840 4325);
PAINT SKYBLUE (-1840 4325);
FORCEPROP 1 LASTPIN (-1800 4250) $PN 2
J 2
(-1805 4260);
DISPLAY 0.617021 (-1805 4260);
PAINT ORANGE (-1805 4260);
FORCEPROP 1 LASTPIN (-1800 4450) $PN 1
J 2
(-1805 4412);
DISPLAY 0.617021 (-1805 4412);
PAINT ORANGE (-1805 4412);
FORCEPROP 2 LAST SEC_TYPE 0402
J 0
(-1850 4575);
DISPLAY 1.021277 (-1850 4575);
PAINT ORANGE (-1850 4575);
DISPLAY INVISIBLE (-1850 4575);
FORCEPROP 2 LAST CDS_LIB mstr_discrete
J 0
(-1800 4350);
PAINT ORANGE (-1800 4350);
DISPLAY INVISIBLE (-1800 4350);
FORCEPROP 2 LAST BOM_COST SM_CONTROLLER
J 2
(-1800 4350);
PAINT MONO (-1800 4350);
DISPLAY INVISIBLE (-1800 4350);
FORCEPROP 2 LAST SEC 1
J 0
(-1850 4575);
DISPLAY 0.680851 (-1850 4575);
PAINT MONO (-1850 4575);
DISPLAY INVISIBLE (-1850 4575);
FORCEPROP 2 LAST CDS_LOCATION R4F4
J 2
(-1845 4475);
DISPLAY 0.617021 (-1845 4475);
PAINT AQUA (-1845 4475);
DISPLAY INVISIBLE (-1845 4475);
FORCEPROP 1 LAST PATH I36
J 2
(-1850 4525);
DISPLAY 0.978723 (-1850 4525);
PAINT WHITE (-1850 4525);
DISPLAY INVISIBLE (-1850 4525);
FORCEPROP 2 LAST ROOM MEM
J 2
(-1850 4525);
PAINT PEACH (-1850 4525);
DISPLAY INVISIBLE (-1850 4525);
FORCEADD PVDDQ_ABC..1
(250 4600);
FORCEPROP 3 LASTPIN (250 4550) SIG_NAME PVDDQ_ABC\g
J 0
(260 4560);
DISPLAY 0.659574 (260 4560);
PAINT MONO (260 4560);
DISPLAY INVISIBLE (260 4560);
FORCEPROP 1 LAST VOLTAGE 1.2V
J 0
(205 4557);
DISPLAY 0.340426 (205 4557);
PAINT SKYBLUE (205 4557);
DISPLAY INVISIBLE (205 4557);
FORCEPROP 2 LAST CDS_LIB mstr_symbols
J 0
(250 4600);
PAINT ORANGE (250 4600);
DISPLAY INVISIBLE (250 4600);
FORCEPROP 1 LAST BODY_TYPE PLUMBING
J 0
(205 4557);
DISPLAY 0.340426 (205 4557);
PAINT GREEN (205 4557);
DISPLAY INVISIBLE (205 4557);
FORCEPROP 1 LAST PATH I37
J 0
(300 4625);
DISPLAY 0.872340 (300 4625);
PAINT AQUA (300 4625);
DISPLAY INVISIBLE (300 4625);
FORCEPROP 1 LAST HDL_POWER PVDDQ_ABC
J 1
(250 4650);
DISPLAY 0.872340 (250 4650);
PAINT GREEN (250 4650);
DISPLAY INVISIBLE (250 4650);
FORCEADD RES..2
R 2
(250 4350);
FORCEPROP 1 LAST PART_NUMBER G21796-026
J 2
(210 4225);
DISPLAY 0.617021 (210 4225);
PAINT BLUE (210 4225);
FORCEPROP 1 LAST VALUE 1.00K
J 2
(205 4425);
DISPLAY 0.617021 (205 4425);
PAINT SKYBLUE (205 4425);
FORCEPROP 1 LAST TOLERANCE 1%
J 2
(205 4375);
DISPLAY 0.617021 (205 4375);
PAINT SKYBLUE (205 4375);
FORCEPROP 1 LAST PACK_TYPE 0402
J 2
(210 4175);
DISPLAY 0.617021 (210 4175);
PAINT SKYBLUE (210 4175);
FORCEPROP 1 LAST MATERIAL CHIP
J 2
(210 4275);
DISPLAY 0.617021 (210 4275);
PAINT SKYBLUE (210 4275);
FORCEPROP 1 LAST WATTAGE 1/16W
J 2
(210 4325);
DISPLAY 0.617021 (210 4325);
PAINT SKYBLUE (210 4325);
FORCEPROP 1 LASTPIN (250 4250) $PN 2
J 2
(245 4260);
DISPLAY 0.617021 (245 4260);
PAINT ORANGE (245 4260);
FORCEPROP 1 LASTPIN (250 4450) $PN 1
J 2
(245 4412);
DISPLAY 0.617021 (245 4412);
PAINT ORANGE (245 4412);
FORCEPROP 1 LAST LOCATION R4G2
J 2
(205 4475);
DISPLAY 0.617021 (205 4475);
PAINT AQUA (205 4475);
FORCEPROP 2 LAST BOM_COST SM_CONTROLLER
J 2
(250 4350);
PAINT MONO (250 4350);
DISPLAY INVISIBLE (250 4350);
FORCEPROP 2 LAST CDS_LIB mstr_discrete
J 0
(250 4350);
PAINT ORANGE (250 4350);
DISPLAY INVISIBLE (250 4350);
FORCEPROP 2 LAST SEC_TYPE 0402
J 0
(200 4575);
DISPLAY 1.021277 (200 4575);
PAINT ORANGE (200 4575);
DISPLAY INVISIBLE (200 4575);
FORCEPROP 2 LAST SEC 1
J 0
(200 4575);
DISPLAY 0.680851 (200 4575);
PAINT MONO (200 4575);
DISPLAY INVISIBLE (200 4575);
FORCEPROP 2 LAST CDS_LOCATION R4G2
J 2
(205 4475);
DISPLAY 0.617021 (205 4475);
PAINT AQUA (205 4475);
DISPLAY INVISIBLE (205 4475);
FORCEPROP 1 LAST PATH I38
J 2
(200 4525);
DISPLAY 0.978723 (200 4525);
PAINT WHITE (200 4525);
DISPLAY INVISIBLE (200 4525);
FORCEPROP 2 LAST ROOM MEM
J 2
(200 4525);
PAINT PEACH (200 4525);
DISPLAY INVISIBLE (200 4525);
FORCEADD OFFPAGE..2
(675 4025);
FORCEPROP 2 LAST $XR1 46 
J 0
(954 4025);
DISPLAY 0.638298 (954 4025);
PAINT MONO (954 4025);
FORCEPROP 2 LAST $XR0 45 
J 0
(864 4025);
DISPLAY 0.638298 (864 4025);
PAINT MONO (864 4025);
FORCEPROP 2 LAST CDS_LIB mstr_standard
J 0
(675 4025);
PAINT MONO (675 4025);
DISPLAY INVISIBLE (675 4025);
FORCEPROP 1 LAST OFFPAGE TRUE
J 0
(1000 3900);
PAINT GREEN (1000 3900);
DISPLAY INVISIBLE (1000 3900);
FORCEPROP 1 LAST COMMENT_BODY TRUE
J 0
(630 3930);
DISPLAY 1.170213 (630 3930);
PAINT GREEN (630 3930);
DISPLAY INVISIBLE (630 3930);
FORCEPROP 2 LAST PATH I39
J 0
(850 4100);
DISPLAY 1.021277 (850 4100);
PAINT ORANGE (850 4100);
DISPLAY INVISIBLE (850 4100);
FORCEADD RES..2
R 2
(-1725 3700);
FORCEPROP 1 LAST LOCATION R4F5
J 2
(-1770 3825);
DISPLAY 0.617021 (-1770 3825);
PAINT AQUA (-1770 3825);
FORCEPROP 1 LAST PART_NUMBER G21796-026
J 2
(-1765 3575);
DISPLAY 0.617021 (-1765 3575);
PAINT BLUE (-1765 3575);
FORCEPROP 1 LAST VALUE 1.00K
J 2
(-1770 3775);
DISPLAY 0.617021 (-1770 3775);
PAINT SKYBLUE (-1770 3775);
FORCEPROP 1 LAST TOLERANCE 1%
J 2
(-1770 3725);
DISPLAY 0.617021 (-1770 3725);
PAINT SKYBLUE (-1770 3725);
FORCEPROP 1 LAST PACK_TYPE 0402
J 2
(-1765 3525);
DISPLAY 0.617021 (-1765 3525);
PAINT SKYBLUE (-1765 3525);
FORCEPROP 1 LAST MATERIAL CHIP
J 2
(-1765 3625);
DISPLAY 0.617021 (-1765 3625);
PAINT SKYBLUE (-1765 3625);
FORCEPROP 1 LAST WATTAGE 1/16W
J 2
(-1765 3675);
DISPLAY 0.617021 (-1765 3675);
PAINT SKYBLUE (-1765 3675);
FORCEPROP 1 LASTPIN (-1725 3600) $PN 2
J 2
(-1730 3610);
DISPLAY 0.617021 (-1730 3610);
PAINT ORANGE (-1730 3610);
FORCEPROP 1 LASTPIN (-1725 3800) $PN 1
J 2
(-1730 3762);
DISPLAY 0.617021 (-1730 3762);
PAINT ORANGE (-1730 3762);
FORCEPROP 2 LAST SEC_TYPE 0402
J 0
(-1775 3925);
DISPLAY 1.021277 (-1775 3925);
PAINT ORANGE (-1775 3925);
DISPLAY INVISIBLE (-1775 3925);
FORCEPROP 2 LAST BOM_COST PROC_SOCKET
J 2
(-1725 3700);
PAINT MONO (-1725 3700);
DISPLAY INVISIBLE (-1725 3700);
FORCEPROP 2 LAST CDS_LIB mstr_discrete
J 0
(-1725 3700);
PAINT ORANGE (-1725 3700);
DISPLAY INVISIBLE (-1725 3700);
FORCEPROP 2 LAST SEC 1
J 0
(-1775 3925);
DISPLAY 0.680851 (-1775 3925);
PAINT MONO (-1775 3925);
DISPLAY INVISIBLE (-1775 3925);
FORCEPROP 2 LAST CDS_LOCATION R4F5
J 2
(-1770 3825);
DISPLAY 0.617021 (-1770 3825);
PAINT AQUA (-1770 3825);
DISPLAY INVISIBLE (-1770 3825);
FORCEPROP 1 LAST PATH I4
J 2
(-1775 3875);
DISPLAY 0.978723 (-1775 3875);
PAINT WHITE (-1775 3875);
DISPLAY INVISIBLE (-1775 3875);
FORCEPROP 2 LAST ROOM PROC
J 2
(-1775 3875);
PAINT PEACH (-1775 3875);
DISPLAY INVISIBLE (-1775 3875);
FORCEADD RES..2
R 2
(325 3700);
FORCEPROP 1 LAST LOCATION R4G3
J 2
(280 3825);
DISPLAY 0.617021 (280 3825);
PAINT AQUA (280 3825);
FORCEPROP 1 LAST PART_NUMBER G21796-026
J 2
(285 3575);
DISPLAY 0.617021 (285 3575);
PAINT BLUE (285 3575);
FORCEPROP 1 LAST VALUE 1.00K
J 2
(280 3775);
DISPLAY 0.617021 (280 3775);
PAINT SKYBLUE (280 3775);
FORCEPROP 1 LAST TOLERANCE 1%
J 2
(280 3725);
DISPLAY 0.617021 (280 3725);
PAINT SKYBLUE (280 3725);
FORCEPROP 1 LAST PACK_TYPE 0402
J 2
(285 3525);
DISPLAY 0.617021 (285 3525);
PAINT SKYBLUE (285 3525);
FORCEPROP 1 LAST MATERIAL CHIP
J 2
(285 3625);
DISPLAY 0.617021 (285 3625);
PAINT SKYBLUE (285 3625);
FORCEPROP 1 LAST WATTAGE 1/16W
J 2
(285 3675);
DISPLAY 0.617021 (285 3675);
PAINT SKYBLUE (285 3675);
FORCEPROP 1 LASTPIN (325 3600) $PN 2
J 2
(320 3610);
DISPLAY 0.617021 (320 3610);
PAINT ORANGE (320 3610);
FORCEPROP 1 LASTPIN (325 3800) $PN 1
J 2
(320 3762);
DISPLAY 0.617021 (320 3762);
PAINT ORANGE (320 3762);
FORCEPROP 2 LAST CDS_LIB mstr_discrete
J 0
(325 3700);
PAINT ORANGE (325 3700);
DISPLAY INVISIBLE (325 3700);
FORCEPROP 2 LAST BOM_COST PROC_SOCKET
J 2
(325 3700);
PAINT MONO (325 3700);
DISPLAY INVISIBLE (325 3700);
FORCEPROP 2 LAST SEC_TYPE 0402
J 0
(275 3925);
DISPLAY 1.021277 (275 3925);
PAINT ORANGE (275 3925);
DISPLAY INVISIBLE (275 3925);
FORCEPROP 2 LAST SEC 1
J 0
(275 3925);
DISPLAY 0.680851 (275 3925);
PAINT MONO (275 3925);
DISPLAY INVISIBLE (275 3925);
FORCEPROP 2 LAST CDS_LOCATION R4G3
J 2
(280 3825);
DISPLAY 0.617021 (280 3825);
PAINT AQUA (280 3825);
DISPLAY INVISIBLE (280 3825);
FORCEPROP 1 LAST PATH I40
J 2
(275 3875);
DISPLAY 0.978723 (275 3875);
PAINT WHITE (275 3875);
DISPLAY INVISIBLE (275 3875);
FORCEPROP 2 LAST ROOM PROC
J 2
(275 3875);
PAINT PEACH (275 3875);
DISPLAY INVISIBLE (275 3875);
FORCEADD GND..1
(25 3375);
FORCEPROP 3 LASTPIN (25 3425) SIG_NAME GND\g
J 0
(35 3435);
DISPLAY 0.659574 (35 3435);
PAINT MONO (35 3435);
DISPLAY INVISIBLE (35 3435);
FORCEPROP 1 LAST VOLTAGE 0
J 0
(25 3375);
PAINT SKYBLUE (25 3375);
DISPLAY INVISIBLE (25 3375);
FORCEPROP 1 LAST SIZE 1B
J 0
(100 3325);
DISPLAY 1.170213 (100 3325);
PAINT GREEN (100 3325);
DISPLAY INVISIBLE (100 3325);
FORCEPROP 2 LAST CDS_LIB mstr_symbols
J 0
(25 3375);
PAINT MONO (25 3375);
DISPLAY INVISIBLE (25 3375);
FORCEPROP 1 LAST BODY_TYPE PLUMBING
J 0
(-20 3332);
DISPLAY 0.340426 (-20 3332);
PAINT GREEN (-20 3332);
DISPLAY INVISIBLE (-20 3332);
FORCEPROP 1 LAST PATH I41
J 0
(100 3375);
DISPLAY 0.872340 (100 3375);
PAINT AQUA (100 3375);
DISPLAY INVISIBLE (100 3375);
FORCEPROP 1 LAST HDL_POWER GND
J 0
(25 3525);
DISPLAY 1.170213 (25 3525);
PAINT GREEN (25 3525);
DISPLAY INVISIBLE (25 3525);
FORCEADD RES..1
(25 4025);
FORCEPROP 1 LAST LOCATION R4G1
J 0
(0 4100);
DISPLAY 0.617021 (0 4100);
PAINT AQUA (0 4100);
FORCEPROP 1 LAST PART_NUMBER G21796-274
J 0
(-100 3875);
DISPLAY 0.617021 (-100 3875);
PAINT BLUE (-100 3875);
FORCEPROP 1 LAST VALUE 2
J 2
(-50 3975);
DISPLAY 0.617021 (-50 3975);
PAINT SKYBLUE (-50 3975);
FORCEPROP 1 LAST TOLERANCE 1.0%
J 0
(125 3925);
DISPLAY 0.617021 (125 3925);
PAINT SKYBLUE (125 3925);
FORCEPROP 1 LAST PACK_TYPE 0402
J 0
(-100 3925);
DISPLAY 0.617021 (-100 3925);
PAINT SKYBLUE (-100 3925);
FORCEPROP 1 LAST MATERIAL CHIP
J 0
(250 3975);
DISPLAY 0.617021 (250 3975);
PAINT SKYBLUE (250 3975);
FORCEPROP 1 LAST WATTAGE 1/16W
J 2
(200 3975);
DISPLAY 0.617021 (200 3975);
PAINT SKYBLUE (200 3975);
FORCEPROP 1 LASTPIN (125 4025) $PN 2
J 0
(87 4037);
DISPLAY 0.617021 (87 4037);
PAINT MONO (87 4037);
FORCEPROP 1 LASTPIN (-75 4025) $PN 1
J 0
(-63 4037);
DISPLAY 0.617021 (-63 4037);
PAINT MONO (-63 4037);
FORCEPROP 2 LAST CDS_LIB mstr_discrete
J 0
(25 4025);
PAINT ORANGE (25 4025);
DISPLAY INVISIBLE (25 4025);
FORCEPROP 2 LAST BOM_COST PROC_SOCKET
J 0
(25 4025);
PAINT MONO (25 4025);
DISPLAY INVISIBLE (25 4025);
FORCEPROP 2 LAST SEC_TYPE 0402
J 0
(-25 4225);
PAINT MONO (-25 4225);
DISPLAY INVISIBLE (-25 4225);
FORCEPROP 2 LAST SEC 1
J 0
(-25 4225);
DISPLAY 0.936170 (-25 4225);
PAINT MONO (-25 4225);
DISPLAY INVISIBLE (-25 4225);
FORCEPROP 2 LAST CDS_LOCATION R4G1
J 0
(0 4100);
DISPLAY 0.617021 (0 4100);
PAINT AQUA (0 4100);
DISPLAY INVISIBLE (0 4100);
FORCEPROP 1 LAST PATH I42
J 0
(-25 4175);
DISPLAY 0.978723 (-25 4175);
PAINT WHITE (-25 4175);
DISPLAY INVISIBLE (-25 4175);
FORCEPROP 0 LAST ROOM PROC
J 0
(-50 3950);
DISPLAY 0.617021 (-50 3950);
PAINT ORANGE (-50 3950);
DISPLAY INVISIBLE (-50 3950);
FORCEADD CAP_A..1
(-200 3725);
FORCEPROP 1 LAST LOCATION C4G1
J 0
(-150 3825);
DISPLAY 0.617021 (-150 3825);
PAINT AQUA (-150 3825);
FORCEPROP 1 LAST PART_NUMBER A36096-045
J 0
(-150 3575);
DISPLAY 0.617021 (-150 3575);
PAINT BLUE (-150 3575);
FORCEPROP 1 LAST VALUE 0.01UF
J 0
(-150 3775);
DISPLAY 0.617021 (-150 3775);
PAINT SKYBLUE (-150 3775);
FORCEPROP 1 LAST TOLERANCE 10%
J 0
(-150 3675);
DISPLAY 0.617021 (-150 3675);
PAINT SKYBLUE (-150 3675);
FORCEPROP 1 LAST PACK_TYPE 0402V
J 0
(-150 3525);
DISPLAY 0.617021 (-150 3525);
PAINT SKYBLUE (-150 3525);
FORCEPROP 1 LAST VOLTAGE 25V
J 0
(-150 3725);
DISPLAY 0.617021 (-150 3725);
PAINT SKYBLUE (-150 3725);
FORCEPROP 1 LAST MATERIAL X7R
J 0
(-150 3625);
DISPLAY 0.617021 (-150 3625);
PAINT SKYBLUE (-150 3625);
FORCEPROP 1 LASTPIN (-200 3825) $PN 1
J 0
(-190 3805);
DISPLAY 0.617021 (-190 3805);
PAINT ORANGE (-190 3805);
FORCEPROP 1 LASTPIN (-200 3625) $PN 2
J 0
(-190 3605);
DISPLAY 0.617021 (-190 3605);
PAINT ORANGE (-190 3605);
FORCEPROP 2 LAST CDS_LOCATION C4G1
J 0
(-150 3825);
DISPLAY 0.617021 (-150 3825);
PAINT AQUA (-150 3825);
DISPLAY INVISIBLE (-150 3825);
FORCEPROP 2 LAST BOM_COST SM_CONTROLLER
J 0
(-200 3725);
PAINT MONO (-200 3725);
DISPLAY INVISIBLE (-200 3725);
FORCEPROP 2 LAST CDS_LIB dev_discrete
J 0
(-200 3725);
PAINT ORANGE (-200 3725);
DISPLAY INVISIBLE (-200 3725);
FORCEPROP 2 LAST CDS_SEC 1
J 0
(-150 3875);
PAINT ORANGE (-150 3875);
DISPLAY INVISIBLE (-150 3875);
FORCEPROP 2 LAST SEC_TYPE 0402V
J 0
(-150 3925);
DISPLAY 1.021277 (-150 3925);
PAINT ORANGE (-150 3925);
DISPLAY INVISIBLE (-150 3925);
FORCEPROP 2 LAST SEC 1
J 0
(-150 3925);
DISPLAY 0.680851 (-150 3925);
PAINT MONO (-150 3925);
DISPLAY INVISIBLE (-150 3925);
FORCEPROP 1 LAST PATH I43
J 0
(-150 3875);
DISPLAY 0.978723 (-150 3875);
PAINT WHITE (-150 3875);
DISPLAY INVISIBLE (-150 3875);
FORCEPROP 0 LAST ROOM MEM
J 0
(-150 3475);
DISPLAY 0.978723 (-150 3475);
PAINT ORANGE (-150 3475);
DISPLAY INVISIBLE (-150 3475);
FORCEADD OFFPAGE..1
(-700 4025);
FORCEPROP 2 LAST $XR0 21 
J 0
(-921 4025);
DISPLAY 0.638298 (-921 4025);
PAINT MONO (-921 4025);
FORCEPROP 2 LAST CDS_LIB mstr_standard
J 0
(-700 4025);
PAINT MONO (-700 4025);
DISPLAY INVISIBLE (-700 4025);
FORCEPROP 1 LAST OFFPAGE TRUE
J 0
(-375 3900);
PAINT GREEN (-375 3900);
DISPLAY INVISIBLE (-375 3900);
FORCEPROP 1 LAST COMMENT_BODY TRUE
J 0
(-575 3925);
DISPLAY 1.170213 (-575 3925);
PAINT GREEN (-575 3925);
DISPLAY INVISIBLE (-575 3925);
FORCEPROP 2 LAST PATH I44
J 0
(-875 4075);
DISPLAY 1.021277 (-875 4075);
PAINT ORANGE (-875 4075);
DISPLAY INVISIBLE (-875 4075);
FORCEADD PVDDQ_ABC..1
(2400 4600);
FORCEPROP 3 LASTPIN (2400 4550) SIG_NAME PVDDQ_ABC\g
J 0
(2410 4560);
DISPLAY 0.659574 (2410 4560);
PAINT MONO (2410 4560);
DISPLAY INVISIBLE (2410 4560);
FORCEPROP 1 LAST VOLTAGE 1.2V
J 0
(2355 4557);
DISPLAY 0.340426 (2355 4557);
PAINT SKYBLUE (2355 4557);
DISPLAY INVISIBLE (2355 4557);
FORCEPROP 2 LAST CDS_LIB mstr_symbols
J 0
(2400 4600);
PAINT ORANGE (2400 4600);
DISPLAY INVISIBLE (2400 4600);
FORCEPROP 1 LAST BODY_TYPE PLUMBING
J 0
(2355 4557);
DISPLAY 0.340426 (2355 4557);
PAINT GREEN (2355 4557);
DISPLAY INVISIBLE (2355 4557);
FORCEPROP 1 LAST PATH I45
J 0
(2450 4625);
DISPLAY 0.872340 (2450 4625);
PAINT AQUA (2450 4625);
DISPLAY INVISIBLE (2450 4625);
FORCEPROP 1 LAST HDL_POWER PVDDQ_ABC
J 1
(2400 4650);
DISPLAY 0.872340 (2400 4650);
PAINT GREEN (2400 4650);
DISPLAY INVISIBLE (2400 4650);
FORCEADD RES..2
R 2
(2400 4350);
FORCEPROP 1 LAST LOCATION R4G21
J 2
(2355 4475);
DISPLAY 0.617021 (2355 4475);
PAINT AQUA (2355 4475);
FORCEPROP 1 LAST PART_NUMBER G21796-026
J 2
(2360 4225);
DISPLAY 0.617021 (2360 4225);
PAINT BLUE (2360 4225);
FORCEPROP 1 LAST VALUE 1.00K
J 2
(2355 4425);
DISPLAY 0.617021 (2355 4425);
PAINT SKYBLUE (2355 4425);
FORCEPROP 1 LAST TOLERANCE 1%
J 2
(2355 4375);
DISPLAY 0.617021 (2355 4375);
PAINT SKYBLUE (2355 4375);
FORCEPROP 1 LAST PACK_TYPE 0402
J 2
(2360 4175);
DISPLAY 0.617021 (2360 4175);
PAINT SKYBLUE (2360 4175);
FORCEPROP 1 LAST MATERIAL CHIP
J 2
(2360 4275);
DISPLAY 0.617021 (2360 4275);
PAINT SKYBLUE (2360 4275);
FORCEPROP 1 LAST WATTAGE 1/16W
J 2
(2360 4325);
DISPLAY 0.617021 (2360 4325);
PAINT SKYBLUE (2360 4325);
FORCEPROP 1 LASTPIN (2400 4250) $PN 2
J 2
(2395 4260);
DISPLAY 0.617021 (2395 4260);
PAINT ORANGE (2395 4260);
FORCEPROP 1 LASTPIN (2400 4450) $PN 1
J 2
(2395 4412);
DISPLAY 0.617021 (2395 4412);
PAINT ORANGE (2395 4412);
FORCEPROP 2 LAST BOM_COST SM_CONTROLLER
J 2
(2400 4350);
PAINT MONO (2400 4350);
DISPLAY INVISIBLE (2400 4350);
FORCEPROP 2 LAST CDS_LIB mstr_discrete
J 0
(2400 4350);
PAINT ORANGE (2400 4350);
DISPLAY INVISIBLE (2400 4350);
FORCEPROP 2 LAST SEC_TYPE 0402
J 0
(2350 4575);
DISPLAY 1.021277 (2350 4575);
PAINT ORANGE (2350 4575);
DISPLAY INVISIBLE (2350 4575);
FORCEPROP 2 LAST SEC 1
J 0
(2350 4575);
DISPLAY 0.680851 (2350 4575);
PAINT MONO (2350 4575);
DISPLAY INVISIBLE (2350 4575);
FORCEPROP 2 LAST CDS_LOCATION R4G21
J 2
(2355 4475);
DISPLAY 0.617021 (2355 4475);
PAINT AQUA (2355 4475);
DISPLAY INVISIBLE (2355 4475);
FORCEPROP 1 LAST PATH I46
J 2
(2350 4525);
DISPLAY 0.978723 (2350 4525);
PAINT WHITE (2350 4525);
DISPLAY INVISIBLE (2350 4525);
FORCEPROP 2 LAST ROOM MEM
J 2
(2350 4525);
PAINT PEACH (2350 4525);
DISPLAY INVISIBLE (2350 4525);
FORCEADD OFFPAGE..2
(2825 4025);
FORCEPROP 2 LAST $XR1 48 
J 0
(3104 4025);
DISPLAY 0.638298 (3104 4025);
PAINT MONO (3104 4025);
FORCEPROP 2 LAST $XR0 47 
J 0
(3014 4025);
DISPLAY 0.638298 (3014 4025);
PAINT MONO (3014 4025);
FORCEPROP 2 LAST CDS_LIB mstr_standard
J 0
(2825 4025);
PAINT MONO (2825 4025);
DISPLAY INVISIBLE (2825 4025);
FORCEPROP 1 LAST OFFPAGE TRUE
J 0
(3150 3900);
PAINT GREEN (3150 3900);
DISPLAY INVISIBLE (3150 3900);
FORCEPROP 1 LAST COMMENT_BODY TRUE
J 0
(2780 3930);
DISPLAY 1.170213 (2780 3930);
PAINT GREEN (2780 3930);
DISPLAY INVISIBLE (2780 3930);
FORCEPROP 2 LAST PATH I47
J 0
(3000 4100);
DISPLAY 1.021277 (3000 4100);
PAINT ORANGE (3000 4100);
DISPLAY INVISIBLE (3000 4100);
FORCEADD RES..2
R 2
(2475 3700);
FORCEPROP 1 LAST LOCATION R4G22
J 2
(2430 3825);
DISPLAY 0.617021 (2430 3825);
PAINT AQUA (2430 3825);
FORCEPROP 1 LAST PART_NUMBER G21796-026
J 2
(2435 3575);
DISPLAY 0.617021 (2435 3575);
PAINT BLUE (2435 3575);
FORCEPROP 1 LAST VALUE 1.00K
J 2
(2430 3775);
DISPLAY 0.617021 (2430 3775);
PAINT SKYBLUE (2430 3775);
FORCEPROP 1 LAST TOLERANCE 1%
J 2
(2430 3725);
DISPLAY 0.617021 (2430 3725);
PAINT SKYBLUE (2430 3725);
FORCEPROP 1 LAST PACK_TYPE 0402
J 2
(2435 3525);
DISPLAY 0.617021 (2435 3525);
PAINT SKYBLUE (2435 3525);
FORCEPROP 1 LAST MATERIAL CHIP
J 2
(2435 3625);
DISPLAY 0.617021 (2435 3625);
PAINT SKYBLUE (2435 3625);
FORCEPROP 1 LAST WATTAGE 1/16W
J 2
(2435 3675);
DISPLAY 0.617021 (2435 3675);
PAINT SKYBLUE (2435 3675);
FORCEPROP 1 LASTPIN (2475 3600) $PN 2
J 2
(2470 3610);
DISPLAY 0.617021 (2470 3610);
PAINT ORANGE (2470 3610);
FORCEPROP 1 LASTPIN (2475 3800) $PN 1
J 2
(2470 3762);
DISPLAY 0.617021 (2470 3762);
PAINT ORANGE (2470 3762);
FORCEPROP 2 LAST CDS_LIB mstr_discrete
J 0
(2475 3700);
PAINT ORANGE (2475 3700);
DISPLAY INVISIBLE (2475 3700);
FORCEPROP 2 LAST BOM_COST PROC_SOCKET
J 2
(2475 3700);
PAINT MONO (2475 3700);
DISPLAY INVISIBLE (2475 3700);
FORCEPROP 2 LAST SEC_TYPE 0402
J 0
(2425 3925);
DISPLAY 1.021277 (2425 3925);
PAINT ORANGE (2425 3925);
DISPLAY INVISIBLE (2425 3925);
FORCEPROP 2 LAST SEC 1
J 0
(2425 3925);
DISPLAY 0.680851 (2425 3925);
PAINT MONO (2425 3925);
DISPLAY INVISIBLE (2425 3925);
FORCEPROP 2 LAST CDS_LOCATION R4G22
J 2
(2430 3825);
DISPLAY 0.617021 (2430 3825);
PAINT AQUA (2430 3825);
DISPLAY INVISIBLE (2430 3825);
FORCEPROP 1 LAST PATH I48
J 2
(2425 3875);
DISPLAY 0.978723 (2425 3875);
PAINT WHITE (2425 3875);
DISPLAY INVISIBLE (2425 3875);
FORCEPROP 2 LAST ROOM PROC
J 2
(2425 3875);
PAINT PEACH (2425 3875);
DISPLAY INVISIBLE (2425 3875);
FORCEADD GND..1
(2175 3375);
FORCEPROP 3 LASTPIN (2175 3425) SIG_NAME GND\g
J 0
(2185 3435);
DISPLAY 0.659574 (2185 3435);
PAINT MONO (2185 3435);
DISPLAY INVISIBLE (2185 3435);
FORCEPROP 1 LAST VOLTAGE 0
J 0
(2175 3375);
PAINT SKYBLUE (2175 3375);
DISPLAY INVISIBLE (2175 3375);
FORCEPROP 1 LAST SIZE 1B
J 0
(2250 3325);
DISPLAY 1.170213 (2250 3325);
PAINT GREEN (2250 3325);
DISPLAY INVISIBLE (2250 3325);
FORCEPROP 2 LAST CDS_LIB mstr_symbols
J 0
(2175 3375);
PAINT MONO (2175 3375);
DISPLAY INVISIBLE (2175 3375);
FORCEPROP 1 LAST BODY_TYPE PLUMBING
J 0
(2130 3332);
DISPLAY 0.340426 (2130 3332);
PAINT GREEN (2130 3332);
DISPLAY INVISIBLE (2130 3332);
FORCEPROP 1 LAST PATH I49
J 0
(2250 3375);
DISPLAY 0.872340 (2250 3375);
PAINT AQUA (2250 3375);
DISPLAY INVISIBLE (2250 3375);
FORCEPROP 1 LAST HDL_POWER GND
J 0
(2175 3525);
DISPLAY 1.170213 (2175 3525);
PAINT GREEN (2175 3525);
DISPLAY INVISIBLE (2175 3525);
FORCEADD RES..1
(-2025 4025);
FORCEPROP 1 LAST LOCATION R4F3
J 0
(-2050 4100);
DISPLAY 0.617021 (-2050 4100);
PAINT AQUA (-2050 4100);
FORCEPROP 1 LAST PART_NUMBER G21796-274
J 0
(-2150 3875);
DISPLAY 0.617021 (-2150 3875);
PAINT BLUE (-2150 3875);
FORCEPROP 1 LAST VALUE 2
J 2
(-2100 3975);
DISPLAY 0.617021 (-2100 3975);
PAINT SKYBLUE (-2100 3975);
FORCEPROP 1 LAST TOLERANCE 1.0%
J 0
(-1925 3925);
DISPLAY 0.617021 (-1925 3925);
PAINT SKYBLUE (-1925 3925);
FORCEPROP 1 LAST PACK_TYPE 0402
J 0
(-2150 3925);
DISPLAY 0.617021 (-2150 3925);
PAINT SKYBLUE (-2150 3925);
FORCEPROP 1 LAST MATERIAL CHIP
J 0
(-1800 3975);
DISPLAY 0.617021 (-1800 3975);
PAINT SKYBLUE (-1800 3975);
FORCEPROP 1 LAST WATTAGE 1/16W
J 2
(-1850 3975);
DISPLAY 0.617021 (-1850 3975);
PAINT SKYBLUE (-1850 3975);
FORCEPROP 1 LASTPIN (-1925 4025) $PN 2
J 0
(-1963 4037);
DISPLAY 0.617021 (-1963 4037);
PAINT MONO (-1963 4037);
FORCEPROP 1 LASTPIN (-2125 4025) $PN 1
J 0
(-2113 4037);
DISPLAY 0.617021 (-2113 4037);
PAINT MONO (-2113 4037);
FORCEPROP 2 LAST SEC_TYPE 0402
J 0
(-2075 4225);
PAINT MONO (-2075 4225);
DISPLAY INVISIBLE (-2075 4225);
FORCEPROP 2 LAST BOM_COST PROC_SOCKET
J 0
(-2025 4025);
PAINT MONO (-2025 4025);
DISPLAY INVISIBLE (-2025 4025);
FORCEPROP 2 LAST CDS_LIB mstr_discrete
J 0
(-2025 4025);
PAINT ORANGE (-2025 4025);
DISPLAY INVISIBLE (-2025 4025);
FORCEPROP 2 LAST SEC 1
J 0
(-2075 4225);
DISPLAY 0.936170 (-2075 4225);
PAINT MONO (-2075 4225);
DISPLAY INVISIBLE (-2075 4225);
FORCEPROP 2 LAST CDS_LOCATION R4F3
J 0
(-2050 4100);
DISPLAY 0.617021 (-2050 4100);
PAINT AQUA (-2050 4100);
DISPLAY INVISIBLE (-2050 4100);
FORCEPROP 1 LAST PATH I5
J 0
(-2075 4175);
DISPLAY 0.978723 (-2075 4175);
PAINT WHITE (-2075 4175);
DISPLAY INVISIBLE (-2075 4175);
FORCEPROP 0 LAST ROOM PROC
J 0
(-2100 3950);
DISPLAY 0.617021 (-2100 3950);
PAINT ORANGE (-2100 3950);
DISPLAY INVISIBLE (-2100 3950);
FORCEADD RES..1
(2175 4025);
FORCEPROP 1 LAST LOCATION R4G20
J 0
(2150 4100);
DISPLAY 0.617021 (2150 4100);
PAINT AQUA (2150 4100);
FORCEPROP 1 LAST PART_NUMBER G21796-274
J 0
(2050 3875);
DISPLAY 0.617021 (2050 3875);
PAINT BLUE (2050 3875);
FORCEPROP 1 LAST VALUE 2
J 2
(2100 3975);
DISPLAY 0.617021 (2100 3975);
PAINT SKYBLUE (2100 3975);
FORCEPROP 1 LAST TOLERANCE 1.0%
J 0
(2275 3925);
DISPLAY 0.617021 (2275 3925);
PAINT SKYBLUE (2275 3925);
FORCEPROP 1 LAST PACK_TYPE 0402
J 0
(2050 3925);
DISPLAY 0.617021 (2050 3925);
PAINT SKYBLUE (2050 3925);
FORCEPROP 1 LAST MATERIAL CHIP
J 0
(2400 3975);
DISPLAY 0.617021 (2400 3975);
PAINT SKYBLUE (2400 3975);
FORCEPROP 1 LAST WATTAGE 1/16W
J 2
(2350 3975);
DISPLAY 0.617021 (2350 3975);
PAINT SKYBLUE (2350 3975);
FORCEPROP 1 LASTPIN (2275 4025) $PN 2
J 0
(2237 4037);
DISPLAY 0.617021 (2237 4037);
PAINT MONO (2237 4037);
FORCEPROP 1 LASTPIN (2075 4025) $PN 1
J 0
(2087 4037);
DISPLAY 0.617021 (2087 4037);
PAINT MONO (2087 4037);
FORCEPROP 2 LAST CDS_LIB mstr_discrete
J 0
(2175 4025);
PAINT ORANGE (2175 4025);
DISPLAY INVISIBLE (2175 4025);
FORCEPROP 2 LAST BOM_COST PROC_SOCKET
J 0
(2175 4025);
PAINT MONO (2175 4025);
DISPLAY INVISIBLE (2175 4025);
FORCEPROP 2 LAST SEC_TYPE 0402
J 0
(2125 4225);
PAINT MONO (2125 4225);
DISPLAY INVISIBLE (2125 4225);
FORCEPROP 2 LAST SEC 1
J 0
(2125 4225);
DISPLAY 0.936170 (2125 4225);
PAINT MONO (2125 4225);
DISPLAY INVISIBLE (2125 4225);
FORCEPROP 2 LAST CDS_LOCATION R4G20
J 0
(2150 4100);
DISPLAY 0.617021 (2150 4100);
PAINT AQUA (2150 4100);
DISPLAY INVISIBLE (2150 4100);
FORCEPROP 1 LAST PATH I50
J 0
(2125 4175);
DISPLAY 0.978723 (2125 4175);
PAINT WHITE (2125 4175);
DISPLAY INVISIBLE (2125 4175);
FORCEPROP 0 LAST ROOM PROC
J 0
(2100 3950);
DISPLAY 0.617021 (2100 3950);
PAINT ORANGE (2100 3950);
DISPLAY INVISIBLE (2100 3950);
FORCEADD CAP_A..1
(1950 3725);
FORCEPROP 1 LAST LOCATION C4G17
J 0
(2000 3825);
DISPLAY 0.617021 (2000 3825);
PAINT AQUA (2000 3825);
FORCEPROP 1 LAST PART_NUMBER A36096-045
J 0
(2000 3575);
DISPLAY 0.617021 (2000 3575);
PAINT BLUE (2000 3575);
FORCEPROP 1 LAST VALUE 0.01UF
J 0
(2000 3775);
DISPLAY 0.617021 (2000 3775);
PAINT SKYBLUE (2000 3775);
FORCEPROP 1 LAST TOLERANCE 10%
J 0
(2000 3675);
DISPLAY 0.617021 (2000 3675);
PAINT SKYBLUE (2000 3675);
FORCEPROP 1 LAST PACK_TYPE 0402V
J 0
(2000 3525);
DISPLAY 0.617021 (2000 3525);
PAINT SKYBLUE (2000 3525);
FORCEPROP 1 LAST VOLTAGE 25V
J 0
(2000 3725);
DISPLAY 0.617021 (2000 3725);
PAINT SKYBLUE (2000 3725);
FORCEPROP 1 LAST MATERIAL X7R
J 0
(2000 3625);
DISPLAY 0.617021 (2000 3625);
PAINT SKYBLUE (2000 3625);
FORCEPROP 1 LASTPIN (1950 3825) $PN 1
J 0
(1960 3805);
DISPLAY 0.617021 (1960 3805);
PAINT ORANGE (1960 3805);
FORCEPROP 1 LASTPIN (1950 3625) $PN 2
J 0
(1960 3605);
DISPLAY 0.617021 (1960 3605);
PAINT ORANGE (1960 3605);
FORCEPROP 2 LAST CDS_LOCATION C4G17
J 0
(2000 3825);
DISPLAY 0.617021 (2000 3825);
PAINT AQUA (2000 3825);
DISPLAY INVISIBLE (2000 3825);
FORCEPROP 2 LAST BOM_COST SM_CONTROLLER
J 0
(1950 3725);
PAINT MONO (1950 3725);
DISPLAY INVISIBLE (1950 3725);
FORCEPROP 2 LAST CDS_LIB dev_discrete
J 0
(1950 3725);
PAINT ORANGE (1950 3725);
DISPLAY INVISIBLE (1950 3725);
FORCEPROP 2 LAST CDS_SEC 1
J 0
(2000 3875);
PAINT ORANGE (2000 3875);
DISPLAY INVISIBLE (2000 3875);
FORCEPROP 2 LAST SEC_TYPE 0402V
J 0
(2000 3925);
DISPLAY 1.021277 (2000 3925);
PAINT ORANGE (2000 3925);
DISPLAY INVISIBLE (2000 3925);
FORCEPROP 2 LAST SEC 1
J 0
(2000 3925);
DISPLAY 0.680851 (2000 3925);
PAINT MONO (2000 3925);
DISPLAY INVISIBLE (2000 3925);
FORCEPROP 1 LAST PATH I51
J 0
(2000 3875);
DISPLAY 0.978723 (2000 3875);
PAINT WHITE (2000 3875);
DISPLAY INVISIBLE (2000 3875);
FORCEPROP 0 LAST ROOM MEM
J 0
(2000 3475);
DISPLAY 0.978723 (2000 3475);
PAINT ORANGE (2000 3475);
DISPLAY INVISIBLE (2000 3475);
FORCEADD OFFPAGE..1
(1450 4025);
FORCEPROP 2 LAST $XR0 21 
J 0
(1229 4025);
DISPLAY 0.638298 (1229 4025);
PAINT MONO (1229 4025);
FORCEPROP 2 LAST CDS_LIB mstr_standard
J 0
(1450 4025);
PAINT MONO (1450 4025);
DISPLAY INVISIBLE (1450 4025);
FORCEPROP 1 LAST OFFPAGE TRUE
J 0
(1775 3900);
PAINT GREEN (1775 3900);
DISPLAY INVISIBLE (1775 3900);
FORCEPROP 1 LAST COMMENT_BODY TRUE
J 0
(1575 3925);
DISPLAY 1.170213 (1575 3925);
PAINT GREEN (1575 3925);
DISPLAY INVISIBLE (1575 3925);
FORCEPROP 2 LAST PATH I52
J 0
(1275 4075);
DISPLAY 1.021277 (1275 4075);
PAINT ORANGE (1275 4075);
DISPLAY INVISIBLE (1275 4075);
FORCEADD RES..2
R 2
(225 2675);
FORCEPROP 1 LAST LOCATION R6L13
J 2
(180 2800);
DISPLAY 0.617021 (180 2800);
PAINT AQUA (180 2800);
FORCEPROP 1 LAST PART_NUMBER G21796-026
J 2
(185 2550);
DISPLAY 0.617021 (185 2550);
PAINT BLUE (185 2550);
FORCEPROP 1 LAST VALUE 1.00K
J 2
(180 2750);
DISPLAY 0.617021 (180 2750);
PAINT SKYBLUE (180 2750);
FORCEPROP 1 LAST TOLERANCE 1%
J 2
(180 2700);
DISPLAY 0.617021 (180 2700);
PAINT SKYBLUE (180 2700);
FORCEPROP 1 LAST PACK_TYPE 0402
J 2
(185 2500);
DISPLAY 0.617021 (185 2500);
PAINT SKYBLUE (185 2500);
FORCEPROP 1 LAST MATERIAL CHIP
J 2
(185 2600);
DISPLAY 0.617021 (185 2600);
PAINT SKYBLUE (185 2600);
FORCEPROP 1 LAST WATTAGE 1/16W
J 2
(185 2650);
DISPLAY 0.617021 (185 2650);
PAINT SKYBLUE (185 2650);
FORCEPROP 1 LASTPIN (225 2575) $PN 2
J 2
(220 2585);
DISPLAY 0.617021 (220 2585);
PAINT ORANGE (220 2585);
FORCEPROP 1 LASTPIN (225 2775) $PN 1
J 2
(220 2737);
DISPLAY 0.617021 (220 2737);
PAINT ORANGE (220 2737);
FORCEPROP 2 LAST BOM_COST SM_CONTROLLER
J 2
(225 2675);
PAINT MONO (225 2675);
DISPLAY INVISIBLE (225 2675);
FORCEPROP 2 LAST CDS_LIB mstr_discrete
J 0
(225 2675);
PAINT ORANGE (225 2675);
DISPLAY INVISIBLE (225 2675);
FORCEPROP 2 LAST SEC_TYPE 0402
J 0
(175 2900);
DISPLAY 1.021277 (175 2900);
PAINT ORANGE (175 2900);
DISPLAY INVISIBLE (175 2900);
FORCEPROP 2 LAST SEC 1
J 0
(175 2900);
DISPLAY 0.680851 (175 2900);
PAINT MONO (175 2900);
DISPLAY INVISIBLE (175 2900);
FORCEPROP 2 LAST CDS_LOCATION R6L13
J 2
(180 2800);
DISPLAY 0.617021 (180 2800);
PAINT AQUA (180 2800);
DISPLAY INVISIBLE (180 2800);
FORCEPROP 1 LAST PATH I54
J 2
(175 2850);
DISPLAY 0.978723 (175 2850);
PAINT WHITE (175 2850);
DISPLAY INVISIBLE (175 2850);
FORCEPROP 2 LAST ROOM MEM
J 2
(175 2850);
PAINT PEACH (175 2850);
DISPLAY INVISIBLE (175 2850);
FORCEADD OFFPAGE..2
(650 2350);
FORCEPROP 2 LAST $XR1 52 
J 0
(929 2350);
DISPLAY 0.638298 (929 2350);
PAINT MONO (929 2350);
FORCEPROP 2 LAST $XR0 51 
J 0
(839 2350);
DISPLAY 0.638298 (839 2350);
PAINT MONO (839 2350);
FORCEPROP 2 LAST CDS_LIB mstr_standard
J 0
(650 2350);
PAINT MONO (650 2350);
DISPLAY INVISIBLE (650 2350);
FORCEPROP 1 LAST OFFPAGE TRUE
J 0
(975 2225);
PAINT GREEN (975 2225);
DISPLAY INVISIBLE (975 2225);
FORCEPROP 1 LAST COMMENT_BODY TRUE
J 0
(605 2255);
DISPLAY 1.170213 (605 2255);
PAINT GREEN (605 2255);
DISPLAY INVISIBLE (605 2255);
FORCEPROP 2 LAST PATH I55
J 0
(825 2425);
DISPLAY 1.021277 (825 2425);
PAINT ORANGE (825 2425);
DISPLAY INVISIBLE (825 2425);
FORCEADD RES..2
R 2
(300 2025);
FORCEPROP 1 LAST LOCATION R6L12
J 2
(255 2150);
DISPLAY 0.617021 (255 2150);
PAINT AQUA (255 2150);
FORCEPROP 1 LAST PART_NUMBER G21796-026
J 2
(260 1900);
DISPLAY 0.617021 (260 1900);
PAINT BLUE (260 1900);
FORCEPROP 1 LAST VALUE 1.00K
J 2
(255 2100);
DISPLAY 0.617021 (255 2100);
PAINT SKYBLUE (255 2100);
FORCEPROP 1 LAST TOLERANCE 1%
J 2
(255 2050);
DISPLAY 0.617021 (255 2050);
PAINT SKYBLUE (255 2050);
FORCEPROP 1 LAST PACK_TYPE 0402
J 2
(260 1850);
DISPLAY 0.617021 (260 1850);
PAINT SKYBLUE (260 1850);
FORCEPROP 1 LAST MATERIAL CHIP
J 2
(260 1950);
DISPLAY 0.617021 (260 1950);
PAINT SKYBLUE (260 1950);
FORCEPROP 1 LAST WATTAGE 1/16W
J 2
(260 2000);
DISPLAY 0.617021 (260 2000);
PAINT SKYBLUE (260 2000);
FORCEPROP 1 LASTPIN (300 1925) $PN 2
J 2
(295 1935);
DISPLAY 0.617021 (295 1935);
PAINT ORANGE (295 1935);
FORCEPROP 1 LASTPIN (300 2125) $PN 1
J 2
(295 2087);
DISPLAY 0.617021 (295 2087);
PAINT ORANGE (295 2087);
FORCEPROP 2 LAST CDS_LIB mstr_discrete
J 0
(300 2025);
PAINT ORANGE (300 2025);
DISPLAY INVISIBLE (300 2025);
FORCEPROP 2 LAST BOM_COST PROC_SOCKET
J 2
(300 2025);
PAINT MONO (300 2025);
DISPLAY INVISIBLE (300 2025);
FORCEPROP 2 LAST SEC_TYPE 0402
J 0
(250 2250);
DISPLAY 1.021277 (250 2250);
PAINT ORANGE (250 2250);
DISPLAY INVISIBLE (250 2250);
FORCEPROP 2 LAST SEC 1
J 0
(250 2250);
DISPLAY 0.680851 (250 2250);
PAINT MONO (250 2250);
DISPLAY INVISIBLE (250 2250);
FORCEPROP 2 LAST CDS_LOCATION R6L12
J 2
(255 2150);
DISPLAY 0.617021 (255 2150);
PAINT AQUA (255 2150);
DISPLAY INVISIBLE (255 2150);
FORCEPROP 1 LAST PATH I56
J 2
(250 2200);
DISPLAY 0.978723 (250 2200);
PAINT WHITE (250 2200);
DISPLAY INVISIBLE (250 2200);
FORCEPROP 2 LAST ROOM PROC
J 2
(250 2200);
PAINT PEACH (250 2200);
DISPLAY INVISIBLE (250 2200);
FORCEADD GND..1
(0 1700);
FORCEPROP 3 LASTPIN (0 1750) SIG_NAME GND\g
J 0
(10 1760);
DISPLAY 0.659574 (10 1760);
PAINT MONO (10 1760);
DISPLAY INVISIBLE (10 1760);
FORCEPROP 1 LAST VOLTAGE 0
J 0
(0 1700);
PAINT SKYBLUE (0 1700);
DISPLAY INVISIBLE (0 1700);
FORCEPROP 1 LAST SIZE 1B
J 0
(75 1650);
DISPLAY 1.170213 (75 1650);
PAINT GREEN (75 1650);
DISPLAY INVISIBLE (75 1650);
FORCEPROP 2 LAST CDS_LIB mstr_symbols
J 0
(0 1700);
PAINT MONO (0 1700);
DISPLAY INVISIBLE (0 1700);
FORCEPROP 1 LAST BODY_TYPE PLUMBING
J 0
(-45 1657);
DISPLAY 0.340426 (-45 1657);
PAINT GREEN (-45 1657);
DISPLAY INVISIBLE (-45 1657);
FORCEPROP 1 LAST PATH I57
J 0
(75 1700);
DISPLAY 0.872340 (75 1700);
PAINT AQUA (75 1700);
DISPLAY INVISIBLE (75 1700);
FORCEPROP 1 LAST HDL_POWER GND
J 0
(0 1850);
DISPLAY 1.170213 (0 1850);
PAINT GREEN (0 1850);
DISPLAY INVISIBLE (0 1850);
FORCEADD RES..1
(0 2350);
FORCEPROP 1 LAST LOCATION R6L14
J 0
(-25 2425);
DISPLAY 0.617021 (-25 2425);
PAINT AQUA (-25 2425);
FORCEPROP 1 LAST PART_NUMBER G21796-274
J 0
(-125 2200);
DISPLAY 0.617021 (-125 2200);
PAINT BLUE (-125 2200);
FORCEPROP 1 LAST VALUE 2
J 2
(-75 2300);
DISPLAY 0.617021 (-75 2300);
PAINT SKYBLUE (-75 2300);
FORCEPROP 1 LAST TOLERANCE 1.0%
J 0
(100 2250);
DISPLAY 0.617021 (100 2250);
PAINT SKYBLUE (100 2250);
FORCEPROP 1 LAST PACK_TYPE 0402
J 0
(-125 2250);
DISPLAY 0.617021 (-125 2250);
PAINT SKYBLUE (-125 2250);
FORCEPROP 1 LAST MATERIAL CHIP
J 0
(225 2300);
DISPLAY 0.617021 (225 2300);
PAINT SKYBLUE (225 2300);
FORCEPROP 1 LAST WATTAGE 1/16W
J 2
(175 2300);
DISPLAY 0.617021 (175 2300);
PAINT SKYBLUE (175 2300);
FORCEPROP 1 LASTPIN (100 2350) $PN 2
J 0
(62 2362);
DISPLAY 0.617021 (62 2362);
PAINT MONO (62 2362);
FORCEPROP 1 LASTPIN (-100 2350) $PN 1
J 0
(-88 2362);
DISPLAY 0.617021 (-88 2362);
PAINT MONO (-88 2362);
FORCEPROP 2 LAST CDS_LIB mstr_discrete
J 0
(0 2350);
PAINT ORANGE (0 2350);
DISPLAY INVISIBLE (0 2350);
FORCEPROP 2 LAST BOM_COST PROC_SOCKET
J 0
(0 2350);
PAINT MONO (0 2350);
DISPLAY INVISIBLE (0 2350);
FORCEPROP 2 LAST SEC_TYPE 0402
J 0
(-50 2550);
PAINT MONO (-50 2550);
DISPLAY INVISIBLE (-50 2550);
FORCEPROP 2 LAST SEC 1
J 0
(-50 2550);
DISPLAY 0.936170 (-50 2550);
PAINT MONO (-50 2550);
DISPLAY INVISIBLE (-50 2550);
FORCEPROP 2 LAST CDS_LOCATION R6L14
J 0
(-25 2425);
DISPLAY 0.617021 (-25 2425);
PAINT AQUA (-25 2425);
DISPLAY INVISIBLE (-25 2425);
FORCEPROP 1 LAST PATH I58
J 0
(-50 2500);
DISPLAY 0.978723 (-50 2500);
PAINT WHITE (-50 2500);
DISPLAY INVISIBLE (-50 2500);
FORCEPROP 0 LAST ROOM PROC
J 0
(-75 2275);
DISPLAY 0.617021 (-75 2275);
PAINT ORANGE (-75 2275);
DISPLAY INVISIBLE (-75 2275);
FORCEADD CAP_A..1
(-225 2050);
FORCEPROP 1 LAST LOCATION C6L7
J 0
(-175 2150);
DISPLAY 0.617021 (-175 2150);
PAINT AQUA (-175 2150);
FORCEPROP 1 LAST PART_NUMBER A36096-045
J 0
(-175 1900);
DISPLAY 0.617021 (-175 1900);
PAINT BLUE (-175 1900);
FORCEPROP 1 LAST VALUE 0.01UF
J 0
(-175 2100);
DISPLAY 0.617021 (-175 2100);
PAINT SKYBLUE (-175 2100);
FORCEPROP 1 LAST TOLERANCE 10%
J 0
(-175 2000);
DISPLAY 0.617021 (-175 2000);
PAINT SKYBLUE (-175 2000);
FORCEPROP 1 LAST PACK_TYPE 0402V
J 0
(-175 1850);
DISPLAY 0.617021 (-175 1850);
PAINT SKYBLUE (-175 1850);
FORCEPROP 1 LAST VOLTAGE 25V
J 0
(-175 2050);
DISPLAY 0.617021 (-175 2050);
PAINT SKYBLUE (-175 2050);
FORCEPROP 1 LAST MATERIAL X7R
J 0
(-175 1950);
DISPLAY 0.617021 (-175 1950);
PAINT SKYBLUE (-175 1950);
FORCEPROP 1 LASTPIN (-225 2150) $PN 1
J 0
(-215 2130);
DISPLAY 0.617021 (-215 2130);
PAINT ORANGE (-215 2130);
FORCEPROP 1 LASTPIN (-225 1950) $PN 2
J 0
(-215 1930);
DISPLAY 0.617021 (-215 1930);
PAINT ORANGE (-215 1930);
FORCEPROP 2 LAST CDS_LOCATION C6L7
J 0
(-175 2150);
DISPLAY 0.617021 (-175 2150);
PAINT AQUA (-175 2150);
DISPLAY INVISIBLE (-175 2150);
FORCEPROP 2 LAST BOM_COST SM_CONTROLLER
J 0
(-225 2050);
PAINT MONO (-225 2050);
DISPLAY INVISIBLE (-225 2050);
FORCEPROP 2 LAST CDS_LIB dev_discrete
J 0
(-225 2050);
PAINT ORANGE (-225 2050);
DISPLAY INVISIBLE (-225 2050);
FORCEPROP 2 LAST CDS_SEC 1
J 0
(-175 2200);
PAINT ORANGE (-175 2200);
DISPLAY INVISIBLE (-175 2200);
FORCEPROP 2 LAST SEC_TYPE 0402V
J 0
(-175 2250);
DISPLAY 1.021277 (-175 2250);
PAINT ORANGE (-175 2250);
DISPLAY INVISIBLE (-175 2250);
FORCEPROP 2 LAST SEC 1
J 0
(-175 2250);
DISPLAY 0.680851 (-175 2250);
PAINT MONO (-175 2250);
DISPLAY INVISIBLE (-175 2250);
FORCEPROP 1 LAST PATH I59
J 0
(-175 2200);
DISPLAY 0.978723 (-175 2200);
PAINT WHITE (-175 2200);
DISPLAY INVISIBLE (-175 2200);
FORCEPROP 0 LAST ROOM MEM
J 0
(-175 1800);
DISPLAY 0.978723 (-175 1800);
PAINT ORANGE (-175 1800);
DISPLAY INVISIBLE (-175 1800);
FORCEADD GND..1
(-2025 3375);
FORCEPROP 3 LASTPIN (-2025 3425) SIG_NAME GND\g
J 0
(-2015 3435);
DISPLAY 0.659574 (-2015 3435);
PAINT MONO (-2015 3435);
DISPLAY INVISIBLE (-2015 3435);
FORCEPROP 1 LAST VOLTAGE 0
J 0
(-2025 3375);
PAINT SKYBLUE (-2025 3375);
DISPLAY INVISIBLE (-2025 3375);
FORCEPROP 2 LAST CDS_LIB mstr_symbols
J 0
(-2025 3375);
PAINT MONO (-2025 3375);
DISPLAY INVISIBLE (-2025 3375);
FORCEPROP 1 LAST SIZE 1B
J 0
(-1950 3325);
DISPLAY 1.170213 (-1950 3325);
PAINT GREEN (-1950 3325);
DISPLAY INVISIBLE (-1950 3325);
FORCEPROP 1 LAST BODY_TYPE PLUMBING
J 0
(-2070 3332);
DISPLAY 0.340426 (-2070 3332);
PAINT GREEN (-2070 3332);
DISPLAY INVISIBLE (-2070 3332);
FORCEPROP 1 LAST PATH I6
J 0
(-1950 3375);
DISPLAY 0.872340 (-1950 3375);
PAINT AQUA (-1950 3375);
DISPLAY INVISIBLE (-1950 3375);
FORCEPROP 1 LAST HDL_POWER GND
J 0
(-2025 3525);
DISPLAY 1.170213 (-2025 3525);
PAINT GREEN (-2025 3525);
DISPLAY INVISIBLE (-2025 3525);
FORCEADD OFFPAGE..1
(-725 2350);
FORCEPROP 2 LAST $XR0 21 
J 0
(-946 2350);
DISPLAY 0.638298 (-946 2350);
PAINT MONO (-946 2350);
FORCEPROP 2 LAST CDS_LIB mstr_standard
J 0
(-725 2350);
PAINT MONO (-725 2350);
DISPLAY INVISIBLE (-725 2350);
FORCEPROP 1 LAST OFFPAGE TRUE
J 0
(-400 2225);
PAINT GREEN (-400 2225);
DISPLAY INVISIBLE (-400 2225);
FORCEPROP 1 LAST COMMENT_BODY TRUE
J 0
(-600 2250);
DISPLAY 1.170213 (-600 2250);
PAINT GREEN (-600 2250);
DISPLAY INVISIBLE (-600 2250);
FORCEPROP 2 LAST PATH I60
J 0
(-900 2400);
DISPLAY 1.021277 (-900 2400);
PAINT ORANGE (-900 2400);
DISPLAY INVISIBLE (-900 2400);
FORCEADD RES..2
R 2
(2400 2650);
FORCEPROP 1 LAST LOCATION R6L2
J 2
(2355 2775);
DISPLAY 0.617021 (2355 2775);
PAINT AQUA (2355 2775);
FORCEPROP 1 LAST PART_NUMBER G21796-026
J 2
(2360 2525);
DISPLAY 0.617021 (2360 2525);
PAINT BLUE (2360 2525);
FORCEPROP 1 LAST VALUE 1.00K
J 2
(2355 2725);
DISPLAY 0.617021 (2355 2725);
PAINT SKYBLUE (2355 2725);
FORCEPROP 1 LAST TOLERANCE 1%
J 2
(2355 2675);
DISPLAY 0.617021 (2355 2675);
PAINT SKYBLUE (2355 2675);
FORCEPROP 1 LAST PACK_TYPE 0402
J 2
(2360 2475);
DISPLAY 0.617021 (2360 2475);
PAINT SKYBLUE (2360 2475);
FORCEPROP 1 LAST MATERIAL CHIP
J 2
(2360 2575);
DISPLAY 0.617021 (2360 2575);
PAINT SKYBLUE (2360 2575);
FORCEPROP 1 LAST WATTAGE 1/16W
J 2
(2360 2625);
DISPLAY 0.617021 (2360 2625);
PAINT SKYBLUE (2360 2625);
FORCEPROP 1 LASTPIN (2400 2550) $PN 2
J 2
(2395 2560);
DISPLAY 0.617021 (2395 2560);
PAINT ORANGE (2395 2560);
FORCEPROP 1 LASTPIN (2400 2750) $PN 1
J 2
(2395 2712);
DISPLAY 0.617021 (2395 2712);
PAINT ORANGE (2395 2712);
FORCEPROP 2 LAST BOM_COST SM_CONTROLLER
J 2
(2400 2650);
PAINT MONO (2400 2650);
DISPLAY INVISIBLE (2400 2650);
FORCEPROP 2 LAST CDS_LIB mstr_discrete
J 0
(2400 2650);
PAINT ORANGE (2400 2650);
DISPLAY INVISIBLE (2400 2650);
FORCEPROP 2 LAST SEC_TYPE 0402
J 0
(2350 2875);
DISPLAY 1.021277 (2350 2875);
PAINT ORANGE (2350 2875);
DISPLAY INVISIBLE (2350 2875);
FORCEPROP 2 LAST SEC 1
J 0
(2350 2875);
DISPLAY 0.680851 (2350 2875);
PAINT MONO (2350 2875);
DISPLAY INVISIBLE (2350 2875);
FORCEPROP 2 LAST CDS_LOCATION R6L2
J 2
(2355 2775);
DISPLAY 0.617021 (2355 2775);
PAINT AQUA (2355 2775);
DISPLAY INVISIBLE (2355 2775);
FORCEPROP 1 LAST PATH I62
J 2
(2350 2825);
DISPLAY 0.978723 (2350 2825);
PAINT WHITE (2350 2825);
DISPLAY INVISIBLE (2350 2825);
FORCEPROP 2 LAST ROOM MEM
J 2
(2350 2825);
PAINT PEACH (2350 2825);
DISPLAY INVISIBLE (2350 2825);
FORCEADD OFFPAGE..2
(2825 2325);
FORCEPROP 2 LAST $XR1 54 
J 0
(3104 2325);
DISPLAY 0.638298 (3104 2325);
PAINT MONO (3104 2325);
FORCEPROP 2 LAST $XR0 53 
J 0
(3014 2325);
DISPLAY 0.638298 (3014 2325);
PAINT MONO (3014 2325);
FORCEPROP 2 LAST CDS_LIB mstr_standard
J 0
(2825 2325);
PAINT MONO (2825 2325);
DISPLAY INVISIBLE (2825 2325);
FORCEPROP 1 LAST OFFPAGE TRUE
J 0
(3150 2200);
PAINT GREEN (3150 2200);
DISPLAY INVISIBLE (3150 2200);
FORCEPROP 1 LAST COMMENT_BODY TRUE
J 0
(2780 2230);
DISPLAY 1.170213 (2780 2230);
PAINT GREEN (2780 2230);
DISPLAY INVISIBLE (2780 2230);
FORCEPROP 2 LAST PATH I63
J 0
(3000 2400);
DISPLAY 1.021277 (3000 2400);
PAINT ORANGE (3000 2400);
DISPLAY INVISIBLE (3000 2400);
FORCEADD RES..2
R 2
(2475 2000);
FORCEPROP 1 LAST LOCATION R6L1
J 2
(2430 2125);
DISPLAY 0.617021 (2430 2125);
PAINT AQUA (2430 2125);
FORCEPROP 1 LAST PART_NUMBER G21796-026
J 2
(2435 1875);
DISPLAY 0.617021 (2435 1875);
PAINT BLUE (2435 1875);
FORCEPROP 1 LAST VALUE 1.00K
J 2
(2430 2075);
DISPLAY 0.617021 (2430 2075);
PAINT SKYBLUE (2430 2075);
FORCEPROP 1 LAST TOLERANCE 1%
J 2
(2430 2025);
DISPLAY 0.617021 (2430 2025);
PAINT SKYBLUE (2430 2025);
FORCEPROP 1 LAST PACK_TYPE 0402
J 2
(2435 1825);
DISPLAY 0.617021 (2435 1825);
PAINT SKYBLUE (2435 1825);
FORCEPROP 1 LAST MATERIAL CHIP
J 2
(2435 1925);
DISPLAY 0.617021 (2435 1925);
PAINT SKYBLUE (2435 1925);
FORCEPROP 1 LAST WATTAGE 1/16W
J 2
(2435 1975);
DISPLAY 0.617021 (2435 1975);
PAINT SKYBLUE (2435 1975);
FORCEPROP 1 LASTPIN (2475 1900) $PN 2
J 2
(2470 1910);
DISPLAY 0.617021 (2470 1910);
PAINT ORANGE (2470 1910);
FORCEPROP 1 LASTPIN (2475 2100) $PN 1
J 2
(2470 2062);
DISPLAY 0.617021 (2470 2062);
PAINT ORANGE (2470 2062);
FORCEPROP 2 LAST CDS_LIB mstr_discrete
J 0
(2475 2000);
PAINT ORANGE (2475 2000);
DISPLAY INVISIBLE (2475 2000);
FORCEPROP 2 LAST BOM_COST PROC_SOCKET
J 2
(2475 2000);
PAINT MONO (2475 2000);
DISPLAY INVISIBLE (2475 2000);
FORCEPROP 2 LAST SEC_TYPE 0402
J 0
(2425 2225);
DISPLAY 1.021277 (2425 2225);
PAINT ORANGE (2425 2225);
DISPLAY INVISIBLE (2425 2225);
FORCEPROP 2 LAST SEC 1
J 0
(2425 2225);
DISPLAY 0.680851 (2425 2225);
PAINT MONO (2425 2225);
DISPLAY INVISIBLE (2425 2225);
FORCEPROP 2 LAST CDS_LOCATION R6L1
J 2
(2430 2125);
DISPLAY 0.617021 (2430 2125);
PAINT AQUA (2430 2125);
DISPLAY INVISIBLE (2430 2125);
FORCEPROP 1 LAST PATH I64
J 2
(2425 2175);
DISPLAY 0.978723 (2425 2175);
PAINT WHITE (2425 2175);
DISPLAY INVISIBLE (2425 2175);
FORCEPROP 2 LAST ROOM PROC
J 2
(2425 2175);
PAINT PEACH (2425 2175);
DISPLAY INVISIBLE (2425 2175);
FORCEADD GND..1
(2175 1675);
FORCEPROP 3 LASTPIN (2175 1725) SIG_NAME GND\g
J 0
(2185 1735);
DISPLAY 0.659574 (2185 1735);
PAINT MONO (2185 1735);
DISPLAY INVISIBLE (2185 1735);
FORCEPROP 1 LAST VOLTAGE 0
J 0
(2175 1675);
PAINT SKYBLUE (2175 1675);
DISPLAY INVISIBLE (2175 1675);
FORCEPROP 1 LAST SIZE 1B
J 0
(2250 1625);
DISPLAY 1.170213 (2250 1625);
PAINT GREEN (2250 1625);
DISPLAY INVISIBLE (2250 1625);
FORCEPROP 2 LAST CDS_LIB mstr_symbols
J 0
(2175 1675);
PAINT MONO (2175 1675);
DISPLAY INVISIBLE (2175 1675);
FORCEPROP 1 LAST BODY_TYPE PLUMBING
J 0
(2130 1632);
DISPLAY 0.340426 (2130 1632);
PAINT GREEN (2130 1632);
DISPLAY INVISIBLE (2130 1632);
FORCEPROP 1 LAST PATH I65
J 0
(2250 1675);
DISPLAY 0.872340 (2250 1675);
PAINT AQUA (2250 1675);
DISPLAY INVISIBLE (2250 1675);
FORCEPROP 1 LAST HDL_POWER GND
J 0
(2175 1825);
DISPLAY 1.170213 (2175 1825);
PAINT GREEN (2175 1825);
DISPLAY INVISIBLE (2175 1825);
FORCEADD RES..1
(2175 2325);
FORCEPROP 1 LAST LOCATION R6L3
J 0
(2150 2400);
DISPLAY 0.617021 (2150 2400);
PAINT AQUA (2150 2400);
FORCEPROP 1 LAST PART_NUMBER G21796-274
J 0
(2050 2175);
DISPLAY 0.617021 (2050 2175);
PAINT BLUE (2050 2175);
FORCEPROP 1 LAST VALUE 2
J 2
(2100 2275);
DISPLAY 0.617021 (2100 2275);
PAINT SKYBLUE (2100 2275);
FORCEPROP 1 LAST TOLERANCE 1.0%
J 0
(2275 2225);
DISPLAY 0.617021 (2275 2225);
PAINT SKYBLUE (2275 2225);
FORCEPROP 1 LAST PACK_TYPE 0402
J 0
(2050 2225);
DISPLAY 0.617021 (2050 2225);
PAINT SKYBLUE (2050 2225);
FORCEPROP 1 LAST MATERIAL CHIP
J 0
(2400 2275);
DISPLAY 0.617021 (2400 2275);
PAINT SKYBLUE (2400 2275);
FORCEPROP 1 LAST WATTAGE 1/16W
J 2
(2350 2275);
DISPLAY 0.617021 (2350 2275);
PAINT SKYBLUE (2350 2275);
FORCEPROP 1 LASTPIN (2075 2325) $PN 1
J 0
(2087 2337);
DISPLAY 0.617021 (2087 2337);
PAINT MONO (2087 2337);
FORCEPROP 1 LASTPIN (2275 2325) $PN 2
J 0
(2237 2337);
DISPLAY 0.617021 (2237 2337);
PAINT MONO (2237 2337);
FORCEPROP 2 LAST CDS_LIB mstr_discrete
J 0
(2175 2325);
PAINT ORANGE (2175 2325);
DISPLAY INVISIBLE (2175 2325);
FORCEPROP 2 LAST BOM_COST PROC_SOCKET
J 0
(2175 2325);
PAINT MONO (2175 2325);
DISPLAY INVISIBLE (2175 2325);
FORCEPROP 2 LAST SEC_TYPE 0402
J 0
(2125 2525);
PAINT MONO (2125 2525);
DISPLAY INVISIBLE (2125 2525);
FORCEPROP 2 LAST SEC 1
J 0
(2125 2525);
DISPLAY 0.936170 (2125 2525);
PAINT MONO (2125 2525);
DISPLAY INVISIBLE (2125 2525);
FORCEPROP 2 LAST CDS_LOCATION R6L3
J 0
(2150 2400);
DISPLAY 0.617021 (2150 2400);
PAINT AQUA (2150 2400);
DISPLAY INVISIBLE (2150 2400);
FORCEPROP 1 LAST PATH I66
J 0
(2125 2475);
DISPLAY 0.978723 (2125 2475);
PAINT WHITE (2125 2475);
DISPLAY INVISIBLE (2125 2475);
FORCEPROP 0 LAST ROOM PROC
J 0
(2100 2250);
DISPLAY 0.617021 (2100 2250);
PAINT ORANGE (2100 2250);
DISPLAY INVISIBLE (2100 2250);
FORCEADD CAP_A..1
(1950 2025);
FORCEPROP 1 LAST LOCATION C6L2
J 0
(2000 2125);
DISPLAY 0.617021 (2000 2125);
PAINT AQUA (2000 2125);
FORCEPROP 1 LAST PART_NUMBER A36096-045
J 0
(2000 1875);
DISPLAY 0.617021 (2000 1875);
PAINT BLUE (2000 1875);
FORCEPROP 1 LAST VALUE 0.01UF
J 0
(2000 2075);
DISPLAY 0.617021 (2000 2075);
PAINT SKYBLUE (2000 2075);
FORCEPROP 1 LAST TOLERANCE 10%
J 0
(2000 1975);
DISPLAY 0.617021 (2000 1975);
PAINT SKYBLUE (2000 1975);
FORCEPROP 1 LAST PACK_TYPE 0402V
J 0
(2000 1825);
DISPLAY 0.617021 (2000 1825);
PAINT SKYBLUE (2000 1825);
FORCEPROP 1 LAST VOLTAGE 25V
J 0
(2000 2025);
DISPLAY 0.617021 (2000 2025);
PAINT SKYBLUE (2000 2025);
FORCEPROP 1 LAST MATERIAL X7R
J 0
(2000 1925);
DISPLAY 0.617021 (2000 1925);
PAINT SKYBLUE (2000 1925);
FORCEPROP 1 LASTPIN (1950 2125) $PN 1
J 0
(1960 2105);
DISPLAY 0.617021 (1960 2105);
PAINT ORANGE (1960 2105);
FORCEPROP 1 LASTPIN (1950 1925) $PN 2
J 0
(1960 1905);
DISPLAY 0.617021 (1960 1905);
PAINT ORANGE (1960 1905);
FORCEPROP 2 LAST CDS_LOCATION C6L2
J 0
(2000 2125);
DISPLAY 0.617021 (2000 2125);
PAINT AQUA (2000 2125);
DISPLAY INVISIBLE (2000 2125);
FORCEPROP 2 LAST BOM_COST SM_CONTROLLER
J 0
(1950 2025);
PAINT MONO (1950 2025);
DISPLAY INVISIBLE (1950 2025);
FORCEPROP 2 LAST CDS_LIB dev_discrete
J 0
(1950 2025);
PAINT ORANGE (1950 2025);
DISPLAY INVISIBLE (1950 2025);
FORCEPROP 2 LAST CDS_SEC 1
J 0
(2000 2175);
PAINT ORANGE (2000 2175);
DISPLAY INVISIBLE (2000 2175);
FORCEPROP 2 LAST SEC_TYPE 0402V
J 0
(2000 2225);
DISPLAY 1.021277 (2000 2225);
PAINT ORANGE (2000 2225);
DISPLAY INVISIBLE (2000 2225);
FORCEPROP 2 LAST SEC 1
J 0
(2000 2225);
DISPLAY 0.680851 (2000 2225);
PAINT MONO (2000 2225);
DISPLAY INVISIBLE (2000 2225);
FORCEPROP 1 LAST PATH I67
J 0
(2000 2175);
DISPLAY 0.978723 (2000 2175);
PAINT WHITE (2000 2175);
DISPLAY INVISIBLE (2000 2175);
FORCEPROP 0 LAST ROOM MEM
J 0
(2000 1775);
DISPLAY 0.978723 (2000 1775);
PAINT ORANGE (2000 1775);
DISPLAY INVISIBLE (2000 1775);
FORCEADD OFFPAGE..1
(1450 2325);
FORCEPROP 2 LAST $XR0 21 
J 0
(1229 2325);
DISPLAY 0.638298 (1229 2325);
PAINT MONO (1229 2325);
FORCEPROP 2 LAST CDS_LIB mstr_standard
J 0
(1450 2325);
PAINT MONO (1450 2325);
DISPLAY INVISIBLE (1450 2325);
FORCEPROP 1 LAST OFFPAGE TRUE
J 0
(1775 2200);
PAINT GREEN (1775 2200);
DISPLAY INVISIBLE (1775 2200);
FORCEPROP 1 LAST COMMENT_BODY TRUE
J 0
(1575 2225);
DISPLAY 1.170213 (1575 2225);
PAINT GREEN (1575 2225);
DISPLAY INVISIBLE (1575 2225);
FORCEPROP 2 LAST PATH I68
J 0
(1275 2375);
DISPLAY 1.021277 (1275 2375);
PAINT ORANGE (1275 2375);
DISPLAY INVISIBLE (1275 2375);
FORCEADD PVDDQ_DEF..1
(225 2925);
FORCEPROP 3 LASTPIN (225 2875) SIG_NAME PVDDQ_DEF\g
J 0
(235 2885);
DISPLAY 0.659574 (235 2885);
PAINT MONO (235 2885);
DISPLAY INVISIBLE (235 2885);
FORCEPROP 1 LAST VOLTAGE 1.2V
J 0
(180 2882);
DISPLAY 0.340426 (180 2882);
PAINT SKYBLUE (180 2882);
DISPLAY INVISIBLE (180 2882);
FORCEPROP 2 LAST CDS_LIB mstr_symbols
J 0
(225 2925);
PAINT ORANGE (225 2925);
DISPLAY INVISIBLE (225 2925);
FORCEPROP 1 LAST BODY_TYPE PLUMBING
J 0
(180 2882);
DISPLAY 0.340426 (180 2882);
PAINT GREEN (180 2882);
DISPLAY INVISIBLE (180 2882);
FORCEPROP 1 LAST PATH I69
J 0
(275 2950);
DISPLAY 0.872340 (275 2950);
PAINT AQUA (275 2950);
DISPLAY INVISIBLE (275 2950);
FORCEPROP 1 LAST HDL_POWER PVDDQ_DEF
J 1
(225 2975);
DISPLAY 0.872340 (225 2975);
PAINT GREEN (225 2975);
DISPLAY INVISIBLE (225 2975);
FORCEADD CAP_A..1
(-2250 3725);
FORCEPROP 1 LAST LOCATION C4F9
J 0
(-2200 3825);
DISPLAY 0.617021 (-2200 3825);
PAINT AQUA (-2200 3825);
FORCEPROP 1 LAST PART_NUMBER A36096-045
J 0
(-2200 3575);
DISPLAY 0.617021 (-2200 3575);
PAINT BLUE (-2200 3575);
FORCEPROP 1 LAST VALUE 0.01UF
J 0
(-2200 3775);
DISPLAY 0.617021 (-2200 3775);
PAINT SKYBLUE (-2200 3775);
FORCEPROP 1 LAST TOLERANCE 10%
J 0
(-2200 3675);
DISPLAY 0.617021 (-2200 3675);
PAINT SKYBLUE (-2200 3675);
FORCEPROP 1 LAST PACK_TYPE 0402V
J 0
(-2200 3525);
DISPLAY 0.617021 (-2200 3525);
PAINT SKYBLUE (-2200 3525);
FORCEPROP 1 LAST VOLTAGE 25V
J 0
(-2200 3725);
DISPLAY 0.617021 (-2200 3725);
PAINT SKYBLUE (-2200 3725);
FORCEPROP 1 LAST MATERIAL X7R
J 0
(-2200 3625);
DISPLAY 0.617021 (-2200 3625);
PAINT SKYBLUE (-2200 3625);
FORCEPROP 1 LASTPIN (-2250 3825) $PN 1
J 0
(-2240 3805);
DISPLAY 0.617021 (-2240 3805);
PAINT ORANGE (-2240 3805);
FORCEPROP 1 LASTPIN (-2250 3625) $PN 2
J 0
(-2240 3605);
DISPLAY 0.617021 (-2240 3605);
PAINT ORANGE (-2240 3605);
FORCEPROP 2 LAST CDS_LOCATION C4F9
J 0
(-2200 3825);
DISPLAY 0.617021 (-2200 3825);
PAINT AQUA (-2200 3825);
DISPLAY INVISIBLE (-2200 3825);
FORCEPROP 2 LAST BOM_COST SM_CONTROLLER
J 0
(-2250 3725);
PAINT MONO (-2250 3725);
DISPLAY INVISIBLE (-2250 3725);
FORCEPROP 2 LAST CDS_LIB dev_discrete
J 0
(-2250 3725);
PAINT ORANGE (-2250 3725);
DISPLAY INVISIBLE (-2250 3725);
FORCEPROP 2 LAST CDS_SEC 1
J 0
(-2200 3875);
PAINT ORANGE (-2200 3875);
DISPLAY INVISIBLE (-2200 3875);
FORCEPROP 2 LAST SEC_TYPE 0402V
J 0
(-2200 3925);
DISPLAY 1.021277 (-2200 3925);
PAINT ORANGE (-2200 3925);
DISPLAY INVISIBLE (-2200 3925);
FORCEPROP 2 LAST SEC 1
J 0
(-2200 3925);
DISPLAY 0.680851 (-2200 3925);
PAINT MONO (-2200 3925);
DISPLAY INVISIBLE (-2200 3925);
FORCEPROP 1 LAST PATH I7
J 0
(-2200 3875);
DISPLAY 0.978723 (-2200 3875);
PAINT WHITE (-2200 3875);
DISPLAY INVISIBLE (-2200 3875);
FORCEPROP 0 LAST ROOM MEM
J 0
(-2200 3475);
DISPLAY 0.978723 (-2200 3475);
PAINT ORANGE (-2200 3475);
DISPLAY INVISIBLE (-2200 3475);
FORCEADD PVDDQ_DEF..1
(2400 2900);
FORCEPROP 3 LASTPIN (2400 2850) SIG_NAME PVDDQ_DEF\g
J 0
(2410 2860);
DISPLAY 0.659574 (2410 2860);
PAINT MONO (2410 2860);
DISPLAY INVISIBLE (2410 2860);
FORCEPROP 1 LAST VOLTAGE 1.2V
J 0
(2355 2857);
DISPLAY 0.340426 (2355 2857);
PAINT SKYBLUE (2355 2857);
DISPLAY INVISIBLE (2355 2857);
FORCEPROP 2 LAST CDS_LIB mstr_symbols
J 0
(2400 2900);
PAINT ORANGE (2400 2900);
DISPLAY INVISIBLE (2400 2900);
FORCEPROP 1 LAST BODY_TYPE PLUMBING
J 0
(2355 2857);
DISPLAY 0.340426 (2355 2857);
PAINT GREEN (2355 2857);
DISPLAY INVISIBLE (2355 2857);
FORCEPROP 1 LAST PATH I70
J 0
(2450 2925);
DISPLAY 0.872340 (2450 2925);
PAINT AQUA (2450 2925);
DISPLAY INVISIBLE (2450 2925);
FORCEPROP 1 LAST HDL_POWER PVDDQ_DEF
J 1
(2400 2950);
DISPLAY 0.872340 (2400 2950);
PAINT GREEN (2400 2950);
DISPLAY INVISIBLE (2400 2950);
FORCEADD OFFPAGE..1
(-2750 4025);
FORCEPROP 2 LAST $XR0 21 
J 0
(-2971 4025);
DISPLAY 0.638298 (-2971 4025);
PAINT MONO (-2971 4025);
FORCEPROP 2 LAST CDS_LIB mstr_standard
J 0
(-2750 4025);
PAINT MONO (-2750 4025);
DISPLAY INVISIBLE (-2750 4025);
FORCEPROP 1 LAST OFFPAGE TRUE
J 0
(-2425 3900);
PAINT GREEN (-2425 3900);
DISPLAY INVISIBLE (-2425 3900);
FORCEPROP 1 LAST COMMENT_BODY TRUE
J 0
(-2625 3925);
DISPLAY 1.170213 (-2625 3925);
PAINT GREEN (-2625 3925);
DISPLAY INVISIBLE (-2625 3925);
FORCEPROP 2 LAST PATH I8
J 0
(-3000 4075);
DISPLAY 1.021277 (-3000 4075);
PAINT ORANGE (-3000 4075);
DISPLAY INVISIBLE (-3000 4075);
FORCEADD RES..2
R 2
(-1800 2675);
FORCEPROP 1 LAST LOCATION R6M1
J 2
(-1845 2800);
DISPLAY 0.617021 (-1845 2800);
PAINT AQUA (-1845 2800);
FORCEPROP 1 LAST PART_NUMBER G21796-026
J 2
(-1840 2550);
DISPLAY 0.617021 (-1840 2550);
PAINT BLUE (-1840 2550);
FORCEPROP 1 LAST VALUE 1.00K
J 2
(-1845 2750);
DISPLAY 0.617021 (-1845 2750);
PAINT SKYBLUE (-1845 2750);
FORCEPROP 1 LAST TOLERANCE 1%
J 2
(-1845 2700);
DISPLAY 0.617021 (-1845 2700);
PAINT SKYBLUE (-1845 2700);
FORCEPROP 1 LAST PACK_TYPE 0402
J 2
(-1840 2500);
DISPLAY 0.617021 (-1840 2500);
PAINT SKYBLUE (-1840 2500);
FORCEPROP 1 LAST MATERIAL CHIP
J 2
(-1840 2600);
DISPLAY 0.617021 (-1840 2600);
PAINT SKYBLUE (-1840 2600);
FORCEPROP 1 LAST WATTAGE 1/16W
J 2
(-1840 2650);
DISPLAY 0.617021 (-1840 2650);
PAINT SKYBLUE (-1840 2650);
FORCEPROP 1 LASTPIN (-1800 2575) $PN 2
J 2
(-1805 2585);
DISPLAY 0.617021 (-1805 2585);
PAINT ORANGE (-1805 2585);
FORCEPROP 1 LASTPIN (-1800 2775) $PN 1
J 2
(-1805 2737);
DISPLAY 0.617021 (-1805 2737);
PAINT ORANGE (-1805 2737);
FORCEPROP 2 LAST CDS_LIB mstr_discrete
J 0
(-1800 2675);
PAINT ORANGE (-1800 2675);
DISPLAY INVISIBLE (-1800 2675);
FORCEPROP 2 LAST BOM_COST PROC_SOCKET
J 2
(-1800 2675);
PAINT MONO (-1800 2675);
DISPLAY INVISIBLE (-1800 2675);
FORCEPROP 2 LAST SEC_TYPE 0402
J 0
(-1850 2900);
DISPLAY 1.021277 (-1850 2900);
PAINT ORANGE (-1850 2900);
DISPLAY INVISIBLE (-1850 2900);
FORCEPROP 2 LAST SEC 1
J 0
(-1850 2900);
DISPLAY 0.680851 (-1850 2900);
PAINT MONO (-1850 2900);
DISPLAY INVISIBLE (-1850 2900);
FORCEPROP 2 LAST CDS_LOCATION R6M1
J 2
(-1845 2800);
DISPLAY 0.617021 (-1845 2800);
PAINT AQUA (-1845 2800);
DISPLAY INVISIBLE (-1845 2800);
FORCEPROP 1 LAST PATH I9
J 2
(-1850 2850);
DISPLAY 0.978723 (-1850 2850);
PAINT WHITE (-1850 2850);
DISPLAY INVISIBLE (-1850 2850);
FORCEPROP 2 LAST ROOM MEM
J 2
(-1850 2850);
PAINT PEACH (-1850 2850);
DISPLAY INVISIBLE (-1850 2850);
FORCEADD CAD_NOTE..1
(1125 4875);
FORCEPROP 0 LAST L1 PLACE BETWEEN DIMM_C1 & C2
J 0
(975 4725);
PAINT WHITE (975 4725);
FORCEPROP 2 LAST BOM_COST SM_CONTROLLER
J 0
(975 4825);
PAINT WHITE (975 4825);
DISPLAY INVISIBLE (975 4825);
FORCEPROP 2 LAST CDS_LIB mstr_symbols
J 0
(1125 4875);
PAINT WHITE (1125 4875);
DISPLAY INVISIBLE (1125 4875);
FORCEPROP 1 LAST COMMENT_BODY TRUE
J 0
(1150 4975);
DISPLAY 1.319149 (1150 4975);
PAINT WHITE (1150 4975);
DISPLAY INVISIBLE (1150 4975);
FORCEPROP 2 LAST ROOM BMC
J 0
(975 4825);
PAINT WHITE (975 4825);
DISPLAY INVISIBLE (975 4825);
FORCEADD CAD_NOTE..1
(-3075 3200);
FORCEPROP 0 LAST L1 PLACE BETWEEN DIMM_D1 & D2
J 0
(-3225 3075);
PAINT WHITE (-3225 3075);
FORCEPROP 2 LAST BOM_COST SM_CONTROLLER
J 0
(-3225 3150);
PAINT WHITE (-3225 3150);
DISPLAY INVISIBLE (-3225 3150);
FORCEPROP 2 LAST CDS_LIB mstr_symbols
J 0
(-3075 3200);
PAINT WHITE (-3075 3200);
DISPLAY INVISIBLE (-3075 3200);
FORCEPROP 1 LAST COMMENT_BODY TRUE
J 0
(-3050 3300);
DISPLAY 1.319149 (-3050 3300);
PAINT WHITE (-3050 3300);
DISPLAY INVISIBLE (-3050 3300);
FORCEPROP 2 LAST ROOM BMC
J 0
(-3225 3150);
PAINT WHITE (-3225 3150);
DISPLAY INVISIBLE (-3225 3150);
FORCEADD CAD_NOTE..1
(-1050 3200);
FORCEPROP 0 LAST L1 PLACE BETWEEN DIMM_E1 & E2
J 0
(-1200 3075);
PAINT WHITE (-1200 3075);
FORCEPROP 2 LAST BOM_COST SM_CONTROLLER
J 0
(-1200 3150);
PAINT WHITE (-1200 3150);
DISPLAY INVISIBLE (-1200 3150);
FORCEPROP 2 LAST CDS_LIB mstr_symbols
J 0
(-1050 3200);
PAINT WHITE (-1050 3200);
DISPLAY INVISIBLE (-1050 3200);
FORCEPROP 1 LAST COMMENT_BODY TRUE
J 0
(-1025 3300);
DISPLAY 1.319149 (-1025 3300);
PAINT WHITE (-1025 3300);
DISPLAY INVISIBLE (-1025 3300);
FORCEPROP 2 LAST ROOM BMC
J 0
(-1200 3150);
PAINT WHITE (-1200 3150);
DISPLAY INVISIBLE (-1200 3150);
FORCEADD CAD_NOTE..1
(1125 3175);
FORCEPROP 0 LAST L1 PLACE BETWEEN DIMM_F1 & F2
J 0
(975 3050);
PAINT WHITE (975 3050);
FORCEPROP 2 LAST BOM_COST SM_CONTROLLER
J 0
(975 3125);
PAINT WHITE (975 3125);
DISPLAY INVISIBLE (975 3125);
FORCEPROP 2 LAST CDS_LIB mstr_symbols
J 0
(1125 3175);
PAINT WHITE (1125 3175);
DISPLAY INVISIBLE (1125 3175);
FORCEPROP 1 LAST COMMENT_BODY TRUE
J 0
(1150 3275);
DISPLAY 1.319149 (1150 3275);
PAINT WHITE (1150 3275);
DISPLAY INVISIBLE (1150 3275);
FORCEPROP 2 LAST ROOM BMC
J 0
(975 3125);
PAINT WHITE (975 3125);
DISPLAY INVISIBLE (975 3125);
FORCEADD CAD_NOTE..1
(-1025 4875);
FORCEPROP 0 LAST L1 PLACE BETWEEN DIMM_B1 & B2
J 0
(-1175 4750);
PAINT WHITE (-1175 4750);
FORCEPROP 2 LAST BOM_COST SM_CONTROLLER
J 0
(-1175 4825);
PAINT WHITE (-1175 4825);
DISPLAY INVISIBLE (-1175 4825);
FORCEPROP 2 LAST CDS_LIB mstr_symbols
J 0
(-1025 4875);
PAINT WHITE (-1025 4875);
DISPLAY INVISIBLE (-1025 4875);
FORCEPROP 1 LAST COMMENT_BODY TRUE
J 0
(-1000 4975);
DISPLAY 1.319149 (-1000 4975);
PAINT WHITE (-1000 4975);
DISPLAY INVISIBLE (-1000 4975);
FORCEPROP 2 LAST ROOM BMC
J 0
(-1175 4825);
PAINT WHITE (-1175 4825);
DISPLAY INVISIBLE (-1175 4825);
FORCEADD INTEL_CORP_BPAGE..1
(4025 625);
FORCEPROP 1 LAST CDS_CON_LAST_MODIFIED Fri Jun 16 17:48:39 2017
J 0
(2600 950);
PAINT ORANGE (2600 950);
DISPLAY INVISIBLE (2600 950);
FORCEPROP 1 LAST CUSTOM_TXT_CDS <CURRENT_DESIGN_SHEET> OF <TOTAL_DESIGN_SHEETS>
J 0
(3525 650);
PAINT ORANGE (3525 650);
FORCEPROP 1 LAST CUSTOM_TXT_CDS <CON_LAST_MODIFIED>
J 0
(25 725);
PAINT ORANGE (25 725);
FORCEPROP 2 LAST CUSTOM_TXT_CDS <XR_PAGE_TITLE>
J 0
(-3865 5875);
DISPLAY 0.638298 (-3865 5875);
PAINT PINK (-3865 5875);
DISPLAY INVISIBLE (-3865 5875);
FORCEPROP 1 LAST SCH_TITLE CPU SIDE BAND:CPU0 DIMM CA VREF
J 0
(-3925 675);
DISPLAY 1.212766 (-3925 675);
PAINT ORANGE (-3925 675);
FORCEPROP 2 LAST CDS_LIB mstr_symbols
J 0
(4025 625);
PAINT MONO (4025 625);
DISPLAY INVISIBLE (4025 625);
FORCEPROP 2 LAST PAGE_BORDER TRUE
J 0
(-3865 5875);
DISPLAY 0.638298 (-3865 5875);
PAINT PINK (-3865 5875);
DISPLAY INVISIBLE (-3865 5875);
FORCEPROP 1 LAST COMMENT_BODY TRUE
J 0
(4037 637);
DISPLAY 0.468085 (4037 637);
PAINT GREEN (4037 637);
DISPLAY INVISIBLE (4037 637);
FORCEPROP 2 LAST CDS_XR_PAGE_TITLE CR-98 : @BASEBOARD_FAB2_LIB.BASEBOARD_FAB2(SCH_1):PAGE98
J 0
(-3865 5875);
DISPLAY 0.638298 (-3865 5875);
PAINT PINK (-3865 5875);
DISPLAY INVISIBLE (-3865 5875);
FORCEADD CAD_NOTE..1
(-3075 4875);
FORCEPROP 0 LAST L1 PLACE BETWEEN DIMM_A1 & A2
J 0
(-3225 4750);
PAINT WHITE (-3225 4750);
FORCEPROP 2 LAST CDS_LIB mstr_symbols
J 0
(-3075 4875);
PAINT WHITE (-3075 4875);
DISPLAY INVISIBLE (-3075 4875);
FORCEPROP 2 LAST BOM_COST SM_CONTROLLER
J 0
(-3225 4825);
PAINT WHITE (-3225 4825);
DISPLAY INVISIBLE (-3225 4825);
FORCEPROP 1 LAST COMMENT_BODY TRUE
J 0
(-3050 4975);
DISPLAY 1.319149 (-3050 4975);
PAINT WHITE (-3050 4975);
DISPLAY INVISIBLE (-3050 4975);
FORCEPROP 2 LAST ROOM BMC
J 0
(-3225 4825);
PAINT WHITE (-3225 4825);
DISPLAY INVISIBLE (-3225 4825);
WIRE 16 -1 (-1800 4550)(-1800 4450);
WIRE 16 -1 (-1800 2875)(-1800 2775);
WIRE 16 -1 (-2025 1825)(-2025 1750);
WIRE 16 -1 (-2025 1825)(-1725 1825);
WIRE 16 -1 (-2250 1825)(-2025 1825);
WIRE 16 -1 (-2250 1950)(-2250 1825);
WIRE 16 -1 (-1725 1825)(-1725 1925);
WIRE 16 -1 (250 4550)(250 4450);
WIRE 16 -1 (25 3500)(25 3425);
WIRE 16 -1 (25 3500)(325 3500);
WIRE 16 -1 (-200 3500)(25 3500);
WIRE 16 -1 (-200 3625)(-200 3500);
WIRE 16 -1 (325 3500)(325 3600);
WIRE 16 -1 (2400 4550)(2400 4450);
WIRE 16 -1 (2175 3500)(2175 3425);
WIRE 16 -1 (2175 3500)(2475 3500);
WIRE 16 -1 (1950 3500)(2175 3500);
WIRE 16 -1 (1950 3625)(1950 3500);
WIRE 16 -1 (2475 3500)(2475 3600);
WIRE 16 -1 (0 1825)(0 1750);
WIRE 16 -1 (0 1825)(300 1825);
WIRE 16 -1 (-225 1825)(0 1825);
WIRE 16 -1 (-225 1950)(-225 1825);
WIRE 16 -1 (300 1825)(300 1925);
WIRE 16 -1 (-2025 3500)(-2025 3425);
WIRE 16 -1 (-2025 3500)(-1725 3500);
WIRE 16 -1 (-2250 3500)(-2025 3500);
WIRE 16 -1 (-2250 3625)(-2250 3500);
WIRE 16 -1 (-1725 3500)(-1725 3600);
WIRE 16 -1 (2175 1800)(2175 1725);
WIRE 16 -1 (2175 1800)(2475 1800);
WIRE 16 -1 (1950 1800)(2175 1800);
WIRE 16 -1 (1950 1925)(1950 1800);
WIRE 16 -1 (2475 1800)(2475 1900);
WIRE 16 -1 (225 2875)(225 2775);
WIRE 16 -1 (2400 2850)(2400 2750);
WIRE 16 -1 (-1925 4025)(-1800 4025);
WIRE 16 -1 (-1800 4025)(-1800 4250);
WIRE 16 -1 (-1725 4025)(-1800 4025);
FORCEPROP 2 LAST SIG_NAME M_A_VREF
J 0
(-1750 4035);
DISPLAY 0.617021 (-1750 4035);
PAINT ORANGE (-1750 4035);
WIRE 16 -1 (-1725 3800)(-1725 4025);
WIRE 16 -1 (-1425 4025)(-1725 4025);
WIRE 16 -1 (-2250 2350)(-2700 2350);
FORCEPROP 2 LAST SIG_NAME M_D_CPU_VREF
J 0
(-2625 2360);
DISPLAY 0.617021 (-2625 2360);
PAINT ORANGE (-2625 2360);
WIRE 16 -1 (-2250 2150)(-2250 2350);
WIRE 16 -1 (-2250 2350)(-2125 2350);
WIRE 16 -1 (-2250 4025)(-2700 4025);
FORCEPROP 2 LAST SIG_NAME M_A_CPU_VREF
J 0
(-2625 4035);
DISPLAY 0.617021 (-2625 4035);
PAINT ORANGE (-2625 4035);
WIRE 16 -1 (-2250 3825)(-2250 4025);
WIRE 16 -1 (-2250 4025)(-2125 4025);
WIRE 16 -1 (-1925 2350)(-1800 2350);
WIRE 16 -1 (-1800 2350)(-1800 2575);
WIRE 16 -1 (-1725 2350)(-1800 2350);
FORCEPROP 2 LAST SIG_NAME M_D_VREF
J 0
(-1750 2360);
DISPLAY 0.617021 (-1750 2360);
PAINT ORANGE (-1750 2360);
WIRE 16 -1 (-1425 2350)(-1725 2350);
WIRE 16 -1 (-1725 2125)(-1725 2350);
WIRE 16 -1 (-225 2350)(-675 2350);
FORCEPROP 2 LAST SIG_NAME M_E_CPU_VREF
J 0
(-600 2360);
DISPLAY 0.617021 (-600 2360);
PAINT ORANGE (-600 2360);
WIRE 16 -1 (-225 2150)(-225 2350);
WIRE 16 -1 (-225 2350)(-100 2350);
WIRE 16 -1 (-200 4025)(-650 4025);
FORCEPROP 2 LAST SIG_NAME M_B_CPU_VREF
J 0
(-575 4035);
DISPLAY 0.617021 (-575 4035);
PAINT ORANGE (-575 4035);
WIRE 16 -1 (-200 3825)(-200 4025);
WIRE 16 -1 (-200 4025)(-75 4025);
WIRE 16 -1 (100 2350)(225 2350);
WIRE 16 -1 (225 2350)(225 2575);
WIRE 16 -1 (300 2350)(225 2350);
FORCEPROP 2 LAST SIG_NAME M_E_VREF
J 0
(275 2360);
DISPLAY 0.617021 (275 2360);
PAINT ORANGE (275 2360);
WIRE 16 -1 (600 2350)(300 2350);
WIRE 16 -1 (300 2125)(300 2350);
WIRE 16 -1 (325 3800)(325 4025);
WIRE 16 -1 (625 4025)(325 4025);
WIRE 16 -1 (325 4025)(250 4025);
FORCEPROP 2 LAST SIG_NAME M_B_VREF
J 0
(300 4035);
DISPLAY 0.617021 (300 4035);
PAINT ORANGE (300 4035);
WIRE 16 -1 (250 4025)(250 4250);
WIRE 16 -1 (125 4025)(250 4025);
WIRE 16 -1 (1950 2325)(1500 2325);
FORCEPROP 2 LAST SIG_NAME M_F_CPU_VREF
J 0
(1575 2335);
DISPLAY 0.617021 (1575 2335);
PAINT ORANGE (1575 2335);
WIRE 16 -1 (1950 2125)(1950 2325);
WIRE 16 -1 (1950 2325)(2075 2325);
WIRE 16 -1 (1950 4025)(1500 4025);
FORCEPROP 2 LAST SIG_NAME M_C_CPU_VREF
J 0
(1575 4035);
DISPLAY 0.617021 (1575 4035);
PAINT ORANGE (1575 4035);
WIRE 16 -1 (1950 3825)(1950 4025);
WIRE 16 -1 (1950 4025)(2075 4025);
WIRE 16 -1 (2275 2325)(2400 2325);
WIRE 16 -1 (2400 2325)(2400 2550);
WIRE 16 -1 (2475 2325)(2400 2325);
FORCEPROP 2 LAST SIG_NAME M_F_VREF
J 0
(2450 2335);
DISPLAY 0.617021 (2450 2335);
PAINT ORANGE (2450 2335);
WIRE 16 -1 (2775 2325)(2475 2325);
WIRE 16 -1 (2475 2100)(2475 2325);
WIRE 16 -1 (2475 3800)(2475 4025);
WIRE 16 -1 (2775 4025)(2475 4025);
WIRE 16 -1 (2475 4025)(2400 4025);
FORCEPROP 2 LAST SIG_NAME M_C_VREF
J 0
(2450 4035);
DISPLAY 0.617021 (2450 4035);
PAINT ORANGE (2450 4035);
WIRE 16 -1 (2400 4025)(2400 4250);
WIRE 16 -1 (2275 4025)(2400 4025);
DOT 1 (-1725 2350);
DOT 1 (-1800 2350);
DOT 1 (-2025 1825);
DOT 1 (-2250 2350);
DOT 1 (-2250 4025);
DOT 1 (-2025 3500);
DOT 1 (-1800 4025);
DOT 1 (-1725 4025);
DOT 1 (325 4025);
DOT 1 (250 4025);
DOT 1 (25 3500);
DOT 1 (-200 4025);
DOT 1 (2475 4025);
DOT 1 (2400 4025);
DOT 1 (2175 3500);
DOT 1 (300 2350);
DOT 1 (225 2350);
DOT 1 (0 1825);
DOT 1 (-225 2350);
DOT 1 (2475 2325);
DOT 1 (2400 2325);
DOT 1 (2175 1800);
DOT 1 (1950 2325);
DOT 1 (1950 4025);
QUIT
